G04 ================== begin FILE IDENTIFICATION RECORD ==================*
G04 Layout Name:  13948-1b.brd*
G04 Film Name:    TMASK*
G04 File Format:  Gerber RS274X*
G04 File Origin:  Cadence Allegro 16.5-S045*
G04 Origin Date:  Thu Nov 13 15:45:54 2014*
G04 *
G04 Layer:  VIA CLASS/SOLDERMASK_TOP*
G04 Layer:  PIN/SOLDERMASK_TOP*
G04 Layer:  PACKAGE GEOMETRY/SOLDERMASK_TOP*
G04 Layer:  DRAWING FORMAT/LAYER_PCB_STORY*
G04 Layer:  DRAWING FORMAT/LAYER_SOLDER_T*
G04 Layer:  BOARD GEOMETRY/SOLDERMASK_TOP*
G04 *
G04 Offset:    (0.00 0.00)*
G04 Mirror:    No*
G04 Mode:      Positive*
G04 Rotation:  0*
G04 FullContactRelief:  No*
G04 UndefLineWidth:     6.00*
G04 ================== end FILE IDENTIFICATION RECORD ====================*
%FSLAX35Y35*MOIN*%
%IR0*IPPOS*OFA0.00000B0.00000*MIA0B0*SFA1.00000B1.00000*%
%AMMACRO61*
4,1,40,.013,.017,
-.013,.017,
-.013695,.016939,
-.014368,.016759,
-.015,.016464,
-.015571,.016064,
-.016064,.015571,
-.016464,.015,
-.016759,.014368,
-.016939,.013695,
-.017,.013,
-.017,-.013,
-.016939,-.013695,
-.016759,-.014368,
-.016464,-.015,
-.016064,-.015571,
-.015571,-.016064,
-.015,-.016464,
-.014368,-.016759,
-.013695,-.016939,
-.013,-.017,
.013,-.017,
.013695,-.016939,
.014368,-.016759,
.015,-.016464,
.015571,-.016064,
.016064,-.015571,
.016464,-.015,
.016759,-.014368,
.016939,-.013695,
.017,-.013,
.017,.013,
.016939,.013695,
.016759,.014368,
.016464,.015,
.016064,.015571,
.015571,.016064,
.015,.016464,
.014368,.016759,
.013695,.016939,
.013,.017,
0.0*
%
%ADD61MACRO61*%
%AMMACRO45*
4,1,40,.017,-.013,
.017,.013,
.016939,.013695,
.016759,.014368,
.016464,.015,
.016064,.015571,
.015571,.016064,
.015,.016464,
.014368,.016759,
.013695,.016939,
.013,.017,
-.013,.017,
-.013695,.016939,
-.014368,.016759,
-.015,.016464,
-.015571,.016064,
-.016064,.015571,
-.016464,.015,
-.016759,.014368,
-.016939,.013695,
-.017,.013,
-.017,-.013,
-.016939,-.013695,
-.016759,-.014368,
-.016464,-.015,
-.016064,-.015571,
-.015571,-.016064,
-.015,-.016464,
-.014368,-.016759,
-.013695,-.016939,
-.013,-.017,
.013,-.017,
.013695,-.016939,
.014368,-.016759,
.015,-.016464,
.015571,-.016064,
.016064,-.015571,
.016464,-.015,
.016759,-.014368,
.016939,-.013695,
.017,-.013,
0.0*
%
%ADD45MACRO45*%
%ADD87R,.143X.011*%
%ADD164R,.1X.081*%
%ADD131R,.045X.11*%
%ADD96R,.055X.11*%
%ADD83R,.11X.055*%
%ADD139R,.007X.01*%
%ADD100C,.02*%
%ADD144C,.04*%
%ADD70C,.022*%
%ADD97C,.014*%
%AMMACRO90*
4,1,40,-.007,.004,
-.007,-.004,
-.00697,-.004347,
-.006879,-.004684,
-.006732,-.005,
-.006532,-.005286,
-.006286,-.005532,
-.006,-.005732,
-.005684,-.005879,
-.005347,-.00597,
-.005,-.006,
.005,-.006,
.005347,-.00597,
.005684,-.005879,
.006,-.005732,
.006286,-.005532,
.006532,-.005286,
.006732,-.005,
.006879,-.004684,
.00697,-.004347,
.007,-.004,
.007,.004,
.00697,.004347,
.006879,.004684,
.006732,.005,
.006532,.005286,
.006286,.005532,
.006,.005732,
.005684,.005879,
.005347,.00597,
.005,.006,
-.005,.006,
-.005347,.00597,
-.005684,.005879,
-.006,.005732,
-.006286,.005532,
-.006532,.005286,
-.006732,.005,
-.006879,.004684,
-.00697,.004347,
-.007,.004,
0.0*
%
%ADD90MACRO90*%
%ADD43C,.05*%
%ADD38C,.032*%
%ADD152R,.138X.07*%
%AMMACRO95*
4,1,40,.004,.007,
-.004,.007,
-.004347,.00697,
-.004684,.006879,
-.005,.006732,
-.005286,.006532,
-.005532,.006286,
-.005732,.006,
-.005879,.005684,
-.00597,.005347,
-.006,.005,
-.006,-.005,
-.00597,-.005347,
-.005879,-.005684,
-.005732,-.006,
-.005532,-.006286,
-.005286,-.006532,
-.005,-.006732,
-.004684,-.006879,
-.004347,-.00697,
-.004,-.007,
.004,-.007,
.004347,-.00697,
.004684,-.006879,
.005,-.006732,
.005286,-.006532,
.005532,-.006286,
.005732,-.006,
.005879,-.005684,
.00597,-.005347,
.006,-.005,
.006,.005,
.00597,.005347,
.005879,.005684,
.005732,.006,
.005532,.006286,
.005286,.006532,
.005,.006732,
.004684,.006879,
.004347,.00697,
.004,.007,
0.0*
%
%ADD95MACRO95*%
%ADD41R,.028X.126*%
%ADD33R,.008X.06*%
%ADD161C,.034*%
%ADD110C,.052*%
%ADD106C,.043*%
%ADD46C,.016*%
%ADD13C,.061*%
%ADD151R,.135X.085*%
%ADD14C,.08*%
%ADD11C,.062*%
%ADD150C,.054*%
%ADD101C,.018*%
%ADD99C,.045*%
%ADD42R,.028X.165*%
%ADD50C,.046*%
%ADD20C,.028*%
%ADD166C,.038*%
%ADD59C,.056*%
%ADD160C,.048*%
%ADD107C,.066*%
%ADD105C,.093*%
%ADD165C,.058*%
%ADD116R,.098X.135*%
%AMMACRO129*
4,1,46,.018,-.00177,
.017918,-.003163,
.017595,-.00452,
.017042,-.0058,
.016274,-.006965,
.015316,-.007979,
.014196,-.008812,
.012949,-.009437,
.011613,-.009836,
.010227,-.009997,
.01,-.01,
-.01,-.01,
-.01,-.00999,
-.011389,-.009868,
-.012737,-.009507,
-.014001,-.008918,
-.015143,-.008118,
-.016129,-.007132,
-.016929,-.005989,
-.017519,-.004725,
-.01788,-.003378,
-.018001,-.001989,
-.018,-.00185,
-.018,.00185,
-.017903,.003241,
-.017565,.004595,
-.016998,.005869,
-.016218,.007025,
-.015249,.008028,
-.01412,.008848,
-.012867,.009459,
-.011526,.009843,
-.010139,.009989,
-.01,.00999,
-.01,.01,
.01,.01,
.01139,.009878,
.012737,.009517,
.014002,.008928,
.015144,.008128,
.016131,.007141,
.016931,.005998,
.017521,.004734,
.017882,.003387,
.018003,.001997,
.018,.00177,
.018,-.00177,
0.0*
%
%ADD129MACRO129*%
%ADD12C,.086*%
%ADD134R,.062X.062*%
%AMMACRO132*
4,1,40,.0225,-.007,
.022378,-.008389,
.022018,-.009736,
.021428,-.011,
.020628,-.012142,
.019642,-.013128,
.0185,-.013928,
.017236,-.014518,
.015889,-.014878,
.0145,-.015,
-.0145,-.015,
-.015889,-.014878,
-.017236,-.014518,
-.0185,-.013928,
-.019642,-.013128,
-.020628,-.012142,
-.021428,-.011,
-.022018,-.009736,
-.022378,-.008389,
-.0225,-.007,
-.0225,.007,
-.022378,.008389,
-.022018,.009736,
-.021428,.011,
-.020628,.012142,
-.019642,.013128,
-.0185,.013928,
-.017236,.014518,
-.015889,.014878,
-.0145,.015,
.0145,.015,
.015889,.014878,
.017236,.014518,
.0185,.013928,
.019642,.013128,
.020628,.012142,
.021428,.011,
.022018,.009736,
.022378,.008389,
.0225,.007,
.0225,-.007,
0.0*
%
%ADD132MACRO132*%
%ADD108C,.078*%
%ADD98R,.045X.045*%
%AMMACRO49*
4,1,40,-.007,-.0225,
-.008389,-.022378,
-.009736,-.022018,
-.011,-.021428,
-.012142,-.020628,
-.013128,-.019642,
-.013928,-.0185,
-.014518,-.017236,
-.014878,-.015889,
-.015,-.0145,
-.015,.0145,
-.014878,.015889,
-.014518,.017236,
-.013928,.0185,
-.013128,.019642,
-.012142,.020628,
-.011,.021428,
-.009736,.022018,
-.008389,.022378,
-.007,.0225,
.007,.0225,
.008389,.022378,
.009736,.022018,
.011,.021428,
.012142,.020628,
.013128,.019642,
.013928,.0185,
.014518,.017236,
.014878,.015889,
.015,.0145,
.015,-.0145,
.014878,-.015889,
.014518,-.017236,
.013928,-.0185,
.013128,-.019642,
.012142,-.020628,
.011,-.021428,
.009736,-.022018,
.008389,-.022378,
.007,-.0225,
-.007,-.0225,
0.0*
%
%ADD49MACRO49*%
%AMMACRO21*
4,1,40,.011,-.007,
.011,.007,
.010939,.007695,
.010759,.008368,
.010464,.009,
.010064,.009571,
.009571,.010064,
.009,.010464,
.008368,.010759,
.007695,.010939,
.007,.011,
-.007,.011,
-.007695,.010939,
-.008368,.010759,
-.009,.010464,
-.009571,.010064,
-.010064,.009571,
-.010464,.009,
-.010759,.008368,
-.010939,.007695,
-.011,.007,
-.011,-.007,
-.010939,-.007695,
-.010759,-.008368,
-.010464,-.009,
-.010064,-.009571,
-.009571,-.010064,
-.009,-.010464,
-.008368,-.010759,
-.007695,-.010939,
-.007,-.011,
.007,-.011,
.007695,-.010939,
.008368,-.010759,
.009,-.010464,
.009571,-.010064,
.010064,-.009571,
.010464,-.009,
.010759,-.008368,
.010939,-.007695,
.011,-.007,
0.0*
%
%ADD21MACRO21*%
%AMMACRO18*
4,1,40,.007,.011,
-.007,.011,
-.007695,.010939,
-.008368,.010759,
-.009,.010464,
-.009571,.010064,
-.010064,.009571,
-.010464,.009,
-.010759,.008368,
-.010939,.007695,
-.011,.007,
-.011,-.007,
-.010939,-.007695,
-.010759,-.008368,
-.010464,-.009,
-.010064,-.009571,
-.009571,-.010064,
-.009,-.010464,
-.008368,-.010759,
-.007695,-.010939,
-.007,-.011,
.007,-.011,
.007695,-.010939,
.008368,-.010759,
.009,-.010464,
.009571,-.010064,
.010064,-.009571,
.010464,-.009,
.010759,-.008368,
.010939,-.007695,
.011,-.007,
.011,.007,
.010939,.007695,
.010759,.008368,
.010464,.009,
.010064,.009571,
.009571,.010064,
.009,.010464,
.008368,.010759,
.007695,.010939,
.007,.011,
0.0*
%
%ADD18MACRO18*%
%AMMACRO79*
4,1,40,-.023,.005,
-.023,-.005,
-.022878,-.006389,
-.022518,-.007736,
-.021928,-.009,
-.021128,-.010142,
-.020142,-.011128,
-.019,-.011928,
-.017736,-.012518,
-.016389,-.012878,
-.015,-.013,
.015,-.013,
.016389,-.012878,
.017736,-.012518,
.019,-.011928,
.020142,-.011128,
.021128,-.010142,
.021928,-.009,
.022518,-.007736,
.022878,-.006389,
.023,-.005,
.023,.005,
.022878,.006389,
.022518,.007736,
.021928,.009,
.021128,.010142,
.020142,.011128,
.019,.011928,
.017736,.012518,
.016389,.012878,
.015,.013,
-.015,.013,
-.016389,.012878,
-.017736,.012518,
-.019,.011928,
-.020142,.011128,
-.021128,.010142,
-.021928,.009,
-.022518,.007736,
-.022878,.006389,
-.023,.005,
0.0*
%
%ADD79MACRO79*%
%AMMACRO153*
4,1,40,.005,.023,
-.005,.023,
-.006389,.022878,
-.007736,.022518,
-.009,.021928,
-.010142,.021128,
-.011128,.020142,
-.011928,.019,
-.012518,.017736,
-.012878,.016389,
-.013,.015,
-.013,-.015,
-.012878,-.016389,
-.012518,-.017736,
-.011928,-.019,
-.011128,-.020142,
-.010142,-.021128,
-.009,-.021928,
-.007736,-.022518,
-.006389,-.022878,
-.005,-.023,
.005,-.023,
.006389,-.022878,
.007736,-.022518,
.009,-.021928,
.010142,-.021128,
.011128,-.020142,
.011928,-.019,
.012518,-.017736,
.012878,-.016389,
.013,-.015,
.013,.015,
.012878,.016389,
.012518,.017736,
.011928,.019,
.011128,.020142,
.010142,.021128,
.009,.021928,
.007736,.022518,
.006389,.022878,
.005,.023,
0.0*
%
%ADD153MACRO153*%
%AMMACRO27*
4,1,40,-.012,.008,
-.012,-.008,
-.011939,-.008695,
-.011759,-.009368,
-.011464,-.01,
-.011064,-.010571,
-.010571,-.011064,
-.01,-.011464,
-.009368,-.011759,
-.008695,-.011939,
-.008,-.012,
.008,-.012,
.008695,-.011939,
.009368,-.011759,
.01,-.011464,
.010571,-.011064,
.011064,-.010571,
.011464,-.01,
.011759,-.009368,
.011939,-.008695,
.012,-.008,
.012,.008,
.011939,.008695,
.011759,.009368,
.011464,.01,
.011064,.010571,
.010571,.011064,
.01,.011464,
.009368,.011759,
.008695,.011939,
.008,.012,
-.008,.012,
-.008695,.011939,
-.009368,.011759,
-.01,.011464,
-.010571,.011064,
-.011064,.010571,
-.011464,.01,
-.011759,.009368,
-.011939,.008695,
-.012,.008,
0.0*
%
%ADD27MACRO27*%
%AMMACRO36*
4,1,40,.008,.012,
-.008,.012,
-.008695,.011939,
-.009368,.011759,
-.01,.011464,
-.010571,.011064,
-.011064,.010571,
-.011464,.01,
-.011759,.009368,
-.011939,.008695,
-.012,.008,
-.012,-.008,
-.011939,-.008695,
-.011759,-.009368,
-.011464,-.01,
-.011064,-.010571,
-.010571,-.011064,
-.01,-.011464,
-.009368,-.011759,
-.008695,-.011939,
-.008,-.012,
.008,-.012,
.008695,-.011939,
.009368,-.011759,
.01,-.011464,
.010571,-.011064,
.011064,-.010571,
.011464,-.01,
.011759,-.009368,
.011939,-.008695,
.012,-.008,
.012,.008,
.011939,.008695,
.011759,.009368,
.011464,.01,
.011064,.010571,
.010571,.011064,
.01,.011464,
.009368,.011759,
.008695,.011939,
.008,.012,
0.0*
%
%ADD36MACRO36*%
%AMMACRO82*
4,1,6,.0135,-.025,
-.0065,-.005,
-.0135,-.005,
-.0135,.005,
-.0065,.005,
.0135,.025,
.0135,-.025,
0.0*
%
%ADD82MACRO82*%
%AMMACRO58*
4,1,40,-.013,-.017,
.013,-.017,
.013695,-.016939,
.014368,-.016759,
.015,-.016464,
.015571,-.016064,
.016064,-.015571,
.016464,-.015,
.016759,-.014368,
.016939,-.013695,
.017,-.013,
.017,.013,
.016939,.013695,
.016759,.014368,
.016464,.015,
.016064,.015571,
.015571,.016064,
.015,.016464,
.014368,.016759,
.013695,.016939,
.013,.017,
-.013,.017,
-.013695,.016939,
-.014368,.016759,
-.015,.016464,
-.015571,.016064,
-.016064,.015571,
-.016464,.015,
-.016759,.014368,
-.016939,.013695,
-.017,.013,
-.017,-.013,
-.016939,-.013695,
-.016759,-.014368,
-.016464,-.015,
-.016064,-.015571,
-.015571,-.016064,
-.015,-.016464,
-.014368,-.016759,
-.013695,-.016939,
-.013,-.017,
0.0*
%
%ADD58MACRO58*%
%AMMACRO29*
4,1,40,-.017,.013,
-.017,-.013,
-.016939,-.013695,
-.016759,-.014368,
-.016464,-.015,
-.016064,-.015571,
-.015571,-.016064,
-.015,-.016464,
-.014368,-.016759,
-.013695,-.016939,
-.013,-.017,
.013,-.017,
.013695,-.016939,
.014368,-.016759,
.015,-.016464,
.015571,-.016064,
.016064,-.015571,
.016464,-.015,
.016759,-.014368,
.016939,-.013695,
.017,-.013,
.017,.013,
.016939,.013695,
.016759,.014368,
.016464,.015,
.016064,.015571,
.015571,.016064,
.015,.016464,
.014368,.016759,
.013695,.016939,
.013,.017,
-.013,.017,
-.013695,.016939,
-.014368,.016759,
-.015,.016464,
-.015571,.016064,
-.016064,.015571,
-.016464,.015,
-.016759,.014368,
-.016939,.013695,
-.017,.013,
0.0*
%
%ADD29MACRO29*%
%AMMACRO113*
4,1,6,-.0135,.005,
-.0065,.005,
.0135,.025,
.0135,-.025,
-.0065,-.005,
-.0135,-.005,
-.0135,.005,
0.0*
%
%ADD113MACRO113*%
%AMMACRO22*
4,1,40,.011,-.007,
.011,.007,
.010939,.007695,
.010759,.008368,
.010464,.009,
.010064,.009571,
.009571,.010064,
.009,.010464,
.008368,.010759,
.007695,.010939,
.007,.011,
-.007,.011,
-.007695,.010939,
-.008368,.010759,
-.009,.010464,
-.009571,.010064,
-.010064,.009571,
-.010464,.009,
-.010759,.008368,
-.010939,.007695,
-.011,.007,
-.011,-.007,
-.010939,-.007695,
-.010759,-.008368,
-.010464,-.009,
-.010064,-.009571,
-.009571,-.010064,
-.009,-.010464,
-.008368,-.010759,
-.007695,-.010939,
-.007,-.011,
.007,-.011,
.007695,-.010939,
.008368,-.010759,
.009,-.010464,
.009571,-.010064,
.010064,-.009571,
.010464,-.009,
.010759,-.008368,
.010939,-.007695,
.011,-.007,
0.0*
%
%ADD22MACRO22*%
%AMMACRO19*
4,1,40,.007,.011,
-.007,.011,
-.007695,.010939,
-.008368,.010759,
-.009,.010464,
-.009571,.010064,
-.010064,.009571,
-.010464,.009,
-.010759,.008368,
-.010939,.007695,
-.011,.007,
-.011,-.007,
-.010939,-.007695,
-.010759,-.008368,
-.010464,-.009,
-.010064,-.009571,
-.009571,-.010064,
-.009,-.010464,
-.008368,-.010759,
-.007695,-.010939,
-.007,-.011,
.007,-.011,
.007695,-.010939,
.008368,-.010759,
.009,-.010464,
.009571,-.010064,
.010064,-.009571,
.010464,-.009,
.010759,-.008368,
.010939,-.007695,
.011,-.007,
.011,.007,
.010939,.007695,
.010759,.008368,
.010464,.009,
.010064,.009571,
.009571,.010064,
.009,.010464,
.008368,.010759,
.007695,.010939,
.007,.011,
0.0*
%
%ADD19MACRO19*%
%AMMACRO26*
4,1,40,-.012,.008,
-.012,-.008,
-.011939,-.008695,
-.011759,-.009368,
-.011464,-.01,
-.011064,-.010571,
-.010571,-.011064,
-.01,-.011464,
-.009368,-.011759,
-.008695,-.011939,
-.008,-.012,
.008,-.012,
.008695,-.011939,
.009368,-.011759,
.01,-.011464,
.010571,-.011064,
.011064,-.010571,
.011464,-.01,
.011759,-.009368,
.011939,-.008695,
.012,-.008,
.012,.008,
.011939,.008695,
.011759,.009368,
.011464,.01,
.011064,.010571,
.010571,.011064,
.01,.011464,
.009368,.011759,
.008695,.011939,
.008,.012,
-.008,.012,
-.008695,.011939,
-.009368,.011759,
-.01,.011464,
-.010571,.011064,
-.011064,.010571,
-.011464,.01,
-.011759,.009368,
-.011939,.008695,
-.012,.008,
0.0*
%
%ADD26MACRO26*%
%AMMACRO37*
4,1,40,.008,.012,
-.008,.012,
-.008695,.011939,
-.009368,.011759,
-.01,.011464,
-.010571,.011064,
-.011064,.010571,
-.011464,.01,
-.011759,.009368,
-.011939,.008695,
-.012,.008,
-.012,-.008,
-.011939,-.008695,
-.011759,-.009368,
-.011464,-.01,
-.011064,-.010571,
-.010571,-.011064,
-.01,-.011464,
-.009368,-.011759,
-.008695,-.011939,
-.008,-.012,
.008,-.012,
.008695,-.011939,
.009368,-.011759,
.01,-.011464,
.010571,-.011064,
.011064,-.010571,
.011464,-.01,
.011759,-.009368,
.011939,-.008695,
.012,-.008,
.012,.008,
.011939,.008695,
.011759,.009368,
.011464,.01,
.011064,.010571,
.010571,.011064,
.01,.011464,
.009368,.011759,
.008695,.011939,
.008,.012,
0.0*
%
%ADD37MACRO37*%
%AMMACRO54*
4,1,40,-.013,-.017,
.013,-.017,
.013695,-.016939,
.014368,-.016759,
.015,-.016464,
.015571,-.016064,
.016064,-.015571,
.016464,-.015,
.016759,-.014368,
.016939,-.013695,
.017,-.013,
.017,.013,
.016939,.013695,
.016759,.014368,
.016464,.015,
.016064,.015571,
.015571,.016064,
.015,.016464,
.014368,.016759,
.013695,.016939,
.013,.017,
-.013,.017,
-.013695,.016939,
-.014368,.016759,
-.015,.016464,
-.015571,.016064,
-.016064,.015571,
-.016464,.015,
-.016759,.014368,
-.016939,.013695,
-.017,.013,
-.017,-.013,
-.016939,-.013695,
-.016759,-.014368,
-.016464,-.015,
-.016064,-.015571,
-.015571,-.016064,
-.015,-.016464,
-.014368,-.016759,
-.013695,-.016939,
-.013,-.017,
0.0*
%
%ADD54MACRO54*%
%AMMACRO30*
4,1,40,-.017,.013,
-.017,-.013,
-.016939,-.013695,
-.016759,-.014368,
-.016464,-.015,
-.016064,-.015571,
-.015571,-.016064,
-.015,-.016464,
-.014368,-.016759,
-.013695,-.016939,
-.013,-.017,
.013,-.017,
.013695,-.016939,
.014368,-.016759,
.015,-.016464,
.015571,-.016064,
.016064,-.015571,
.016464,-.015,
.016759,-.014368,
.016939,-.013695,
.017,-.013,
.017,.013,
.016939,.013695,
.016759,.014368,
.016464,.015,
.016064,.015571,
.015571,.016064,
.015,.016464,
.014368,.016759,
.013695,.016939,
.013,.017,
-.013,.017,
-.013695,.016939,
-.014368,.016759,
-.015,.016464,
-.015571,.016064,
-.016064,.015571,
-.016464,.015,
-.016759,.014368,
-.016939,.013695,
-.017,.013,
0.0*
%
%ADD30MACRO30*%
%ADD89R,.011X.03*%
%ADD88R,.03X.011*%
%ADD73R,.01X.014*%
%ADD177R,.012X.05*%
%ADD173R,.05X.012*%
%ADD127R,.04X.014*%
%ADD77R,.022X.04*%
%ADD68R,.012X.042*%
%ADD66R,.042X.012*%
%ADD40R,.06X.012*%
%ADD176R,.012X.043*%
%ADD172R,.043X.012*%
%ADD104R,.012X.06*%
%ADD56R,.016X.02*%
%ADD55R,.023X.04*%
%ADD157R,.081X.02*%
%ADD148R,.042X.014*%
%ADD147R,.014X.042*%
%ADD112R,.04X.016*%
%ADD74R,.016X.012*%
%ADD47R,.06X.014*%
%ADD23O,.014X.071*%
%ADD142R,.014X.042*%
%ADD140R,.042X.014*%
%ADD137R,.016X.04*%
%ADD118R,.012X.044*%
%ADD71R,.045X.03*%
%ADD65R,.036X.012*%
%ADD64R,.012X.036*%
%ADD28R,.014X.06*%
%ADD133R,.128X.105*%
%ADD128R,.016X.032*%
%ADD125R,.012X.036*%
%ADD122R,.06X.016*%
%ADD120R,.036X.012*%
%ADD39R,.03X.045*%
%ADD179R,.028X.03*%
%ADD159R,.016X.06*%
%ADD136R,.012X.037*%
%ADD135R,.037X.012*%
%ADD124R,.012X.046*%
%ADD121R,.046X.012*%
%AMMACRO93*
4,1,40,-.004,-.007,
.004,-.007,
.004347,-.00697,
.004684,-.006879,
.005,-.006732,
.005286,-.006532,
.005532,-.006286,
.005732,-.006,
.005879,-.005684,
.00597,-.005347,
.006,-.005,
.006,.005,
.00597,.005347,
.005879,.005684,
.005732,.006,
.005532,.006286,
.005286,.006532,
.005,.006732,
.004684,.006879,
.004347,.00697,
.004,.007,
-.004,.007,
-.004347,.00697,
-.004684,.006879,
-.005,.006732,
-.005286,.006532,
-.005532,.006286,
-.005732,.006,
-.005879,.005684,
-.00597,.005347,
-.006,.005,
-.006,-.005,
-.00597,-.005347,
-.005879,-.005684,
-.005732,-.006,
-.005532,-.006286,
-.005286,-.006532,
-.005,-.006732,
-.004684,-.006879,
-.004347,-.00697,
-.004,-.007,
0.0*
%
%ADD93MACRO93*%
%ADD86R,.093X.011*%
%AMMACRO84*
4,1,40,.007,-.004,
.007,.004,
.00697,.004347,
.006879,.004684,
.006732,.005,
.006532,.005286,
.006286,.005532,
.006,.005732,
.005684,.005879,
.005347,.00597,
.005,.006,
-.005,.006,
-.005347,.00597,
-.005684,.005879,
-.006,.005732,
-.006286,.005532,
-.006532,.005286,
-.006732,.005,
-.006879,.004684,
-.00697,.004347,
-.007,.004,
-.007,-.004,
-.00697,-.004347,
-.006879,-.004684,
-.006732,-.005,
-.006532,-.005286,
-.006286,-.005532,
-.006,-.005732,
-.005684,-.005879,
-.005347,-.00597,
-.005,-.006,
.005,-.006,
.005347,-.00597,
.005684,-.005879,
.006,-.005732,
.006286,-.005532,
.006532,-.005286,
.006732,-.005,
.006879,-.004684,
.00697,-.004347,
.007,-.004,
0.0*
%
%ADD84MACRO84*%
%ADD75R,.03X.064*%
%ADD174R,.02X.066*%
%ADD170R,.128X.107*%
%ADD163R,.012X.038*%
%ADD162R,.038X.012*%
%ADD175R,.042X.055*%
%ADD171R,.042X.037*%
%ADD92R,.128X.108*%
%ADD48R,.05X.065*%
%ADD154R,.026X.036*%
%ADD149C,.107*%
%ADD94R,.053X.063*%
%ADD85R,.065X.05*%
%ADD130R,.065X.025*%
%ADD103R,.063X.053*%
%ADD76C,.126*%
%ADD72R,.045X.09*%
%ADD138R,.025X.065*%
%ADD63R,.045X.055*%
%ADD24R,.035X.083*%
%ADD15R,.048X.016*%
%ADD155R,.055X.036*%
%ADD145O,.189X.126*%
%ADD123R,.016X.048*%
%ADD119R,.074X.054*%
%ADD109C,.128*%
%ADD78R,.095X.06*%
%ADD69R,.13X.13*%
%ADD62R,.055X.045*%
%ADD91C,.138*%
%ADD80R,.054X.074*%
%ADD146R,.075X.045*%
%ADD57R,.063X.039*%
%ADD115R,.09X.095*%
%ADD10C,.158*%
%ADD178R,.152X.152*%
%ADD158R,.079X.071*%
%ADD156R,.065X.075*%
%ADD111R,.095X.09*%
%ADD67R,.045X.059*%
%AMMACRO53*
4,1,40,.007,.0225,
.008389,.022378,
.009736,.022018,
.011,.021428,
.012142,.020628,
.013128,.019642,
.013928,.0185,
.014518,.017236,
.014878,.015889,
.015,.0145,
.015,-.0145,
.014878,-.015889,
.014518,-.017236,
.013928,-.0185,
.013128,-.019642,
.012142,-.020628,
.011,-.021428,
.009736,-.022018,
.008389,-.022378,
.007,-.0225,
-.007,-.0225,
-.008389,-.022378,
-.009736,-.022018,
-.011,-.021428,
-.012142,-.020628,
-.013128,-.019642,
-.013928,-.0185,
-.014518,-.017236,
-.014878,-.015889,
-.015,-.0145,
-.015,.0145,
-.014878,.015889,
-.014518,.017236,
-.013928,.0185,
-.013128,.019642,
-.012142,.020628,
-.011,.021428,
-.009736,.022018,
-.008389,.022378,
-.007,.0225,
.007,.0225,
0.0*
%
%ADD53MACRO53*%
%AMMACRO25*
4,1,40,-.0225,.007,
-.022378,.008389,
-.022018,.009736,
-.021428,.011,
-.020628,.012142,
-.019642,.013128,
-.0185,.013928,
-.017236,.014518,
-.015889,.014878,
-.0145,.015,
.0145,.015,
.015889,.014878,
.017236,.014518,
.0185,.013928,
.019642,.013128,
.020628,.012142,
.021428,.011,
.022018,.009736,
.022378,.008389,
.0225,.007,
.0225,-.007,
.022378,-.008389,
.022018,-.009736,
.021428,-.011,
.020628,-.012142,
.019642,-.013128,
.0185,-.013928,
.017236,-.014518,
.015889,-.014878,
.0145,-.015,
-.0145,-.015,
-.015889,-.014878,
-.017236,-.014518,
-.0185,-.013928,
-.019642,-.013128,
-.020628,-.012142,
-.021428,-.011,
-.022018,-.009736,
-.022378,-.008389,
-.0225,-.007,
-.0225,.007,
0.0*
%
%ADD25MACRO25*%
%ADD180R,.057X.039*%
%ADD169R,.055X.069*%
%ADD143R,.035X.098*%
%ADD141R,.128X.128*%
%ADD168R,.049X.069*%
%ADD126R,.183X.183*%
%AMMACRO102*
4,1,40,.024,.012,
.024,-.012,
.023878,-.013389,
.023518,-.014736,
.022928,-.016,
.022128,-.017142,
.021142,-.018128,
.02,-.018928,
.018736,-.019518,
.017389,-.019878,
.016,-.02,
-.016,-.02,
-.017389,-.019878,
-.018736,-.019518,
-.02,-.018928,
-.021142,-.018128,
-.022128,-.017142,
-.022928,-.016,
-.023518,-.014736,
-.023878,-.013389,
-.024,-.012,
-.024,.012,
-.023878,.013389,
-.023518,.014736,
-.022928,.016,
-.022128,.017142,
-.021142,.018128,
-.02,.018928,
-.018736,.019518,
-.017389,.019878,
-.016,.02,
.016,.02,
.017389,.019878,
.018736,.019518,
.02,.018928,
.021142,.018128,
.022128,.017142,
.022928,.016,
.023518,.014736,
.023878,.013389,
.024,.012,
0.0*
%
%ADD102MACRO102*%
%ADD167R,.047X.098*%
%AMMACRO52*
4,1,40,.012,-.008,
.012,.008,
.011939,.008695,
.011759,.009368,
.011464,.01,
.011064,.010571,
.010571,.011064,
.01,.011464,
.009368,.011759,
.008695,.011939,
.008,.012,
-.008,.012,
-.008695,.011939,
-.009368,.011759,
-.01,.011464,
-.010571,.011064,
-.011064,.010571,
-.011464,.01,
-.011759,.009368,
-.011939,.008695,
-.012,.008,
-.012,-.008,
-.011939,-.008695,
-.011759,-.009368,
-.011464,-.01,
-.011064,-.010571,
-.010571,-.011064,
-.01,-.011464,
-.009368,-.011759,
-.008695,-.011939,
-.008,-.012,
.008,-.012,
.008695,-.011939,
.009368,-.011759,
.01,-.011464,
.010571,-.011064,
.011064,-.010571,
.011464,-.01,
.011759,-.009368,
.011939,-.008695,
.012,-.008,
0.0*
%
%ADD52MACRO52*%
%AMMACRO32*
4,1,40,-.008,-.012,
.008,-.012,
.008695,-.011939,
.009368,-.011759,
.01,-.011464,
.010571,-.011064,
.011064,-.010571,
.011464,-.01,
.011759,-.009368,
.011939,-.008695,
.012,-.008,
.012,.008,
.011939,.008695,
.011759,.009368,
.011464,.01,
.011064,.010571,
.010571,.011064,
.01,.011464,
.009368,.011759,
.008695,.011939,
.008,.012,
-.008,.012,
-.008695,.011939,
-.009368,.011759,
-.01,.011464,
-.010571,.011064,
-.011064,.010571,
-.011464,.01,
-.011759,.009368,
-.011939,.008695,
-.012,.008,
-.012,-.008,
-.011939,-.008695,
-.011759,-.009368,
-.011464,-.01,
-.011064,-.010571,
-.010571,-.011064,
-.01,-.011464,
-.009368,-.011759,
-.008695,-.011939,
-.008,-.012,
0.0*
%
%ADD32MACRO32*%
%AMMACRO16*
4,1,40,-.007,-.011,
.007,-.011,
.007695,-.010939,
.008368,-.010759,
.009,-.010464,
.009571,-.010064,
.010064,-.009571,
.010464,-.009,
.010759,-.008368,
.010939,-.007695,
.011,-.007,
.011,.007,
.010939,.007695,
.010759,.008368,
.010464,.009,
.010064,.009571,
.009571,.010064,
.009,.010464,
.008368,.010759,
.007695,.010939,
.007,.011,
-.007,.011,
-.007695,.010939,
-.008368,.010759,
-.009,.010464,
-.009571,.010064,
-.010064,.009571,
-.010464,.009,
-.010759,.008368,
-.010939,.007695,
-.011,.007,
-.011,-.007,
-.010939,-.007695,
-.010759,-.008368,
-.010464,-.009,
-.010064,-.009571,
-.009571,-.010064,
-.009,-.010464,
-.008368,-.010759,
-.007695,-.010939,
-.007,-.011,
0.0*
%
%ADD16MACRO16*%
%AMMACRO34*
4,1,40,-.011,.007,
-.011,-.007,
-.010939,-.007695,
-.010759,-.008368,
-.010464,-.009,
-.010064,-.009571,
-.009571,-.010064,
-.009,-.010464,
-.008368,-.010759,
-.007695,-.010939,
-.007,-.011,
.007,-.011,
.007695,-.010939,
.008368,-.010759,
.009,-.010464,
.009571,-.010064,
.010064,-.009571,
.010464,-.009,
.010759,-.008368,
.010939,-.007695,
.011,-.007,
.011,.007,
.010939,.007695,
.010759,.008368,
.010464,.009,
.010064,.009571,
.009571,.010064,
.009,.010464,
.008368,.010759,
.007695,.010939,
.007,.011,
-.007,.011,
-.007695,.010939,
-.008368,.010759,
-.009,.010464,
-.009571,.010064,
-.010064,.009571,
-.010464,.009,
-.010759,.008368,
-.010939,.007695,
-.011,.007,
0.0*
%
%ADD34MACRO34*%
%AMMACRO114*
4,1,6,-.0135,.025,
.0065,.005,
.0135,.005,
.0135,-.005,
.0065,-.005,
-.0135,-.025,
-.0135,.025,
0.0*
%
%ADD114MACRO114*%
%AMMACRO60*
4,1,40,.013,.017,
-.013,.017,
-.013695,.016939,
-.014368,.016759,
-.015,.016464,
-.015571,.016064,
-.016064,.015571,
-.016464,.015,
-.016759,.014368,
-.016939,.013695,
-.017,.013,
-.017,-.013,
-.016939,-.013695,
-.016759,-.014368,
-.016464,-.015,
-.016064,-.015571,
-.015571,-.016064,
-.015,-.016464,
-.014368,-.016759,
-.013695,-.016939,
-.013,-.017,
.013,-.017,
.013695,-.016939,
.014368,-.016759,
.015,-.016464,
.015571,-.016064,
.016064,-.015571,
.016464,-.015,
.016759,-.014368,
.016939,-.013695,
.017,-.013,
.017,.013,
.016939,.013695,
.016759,.014368,
.016464,.015,
.016064,.015571,
.015571,.016064,
.015,.016464,
.014368,.016759,
.013695,.016939,
.013,.017,
0.0*
%
%ADD60MACRO60*%
%AMMACRO44*
4,1,40,.017,-.013,
.017,.013,
.016939,.013695,
.016759,.014368,
.016464,.015,
.016064,.015571,
.015571,.016064,
.015,.016464,
.014368,.016759,
.013695,.016939,
.013,.017,
-.013,.017,
-.013695,.016939,
-.014368,.016759,
-.015,.016464,
-.015571,.016064,
-.016064,.015571,
-.016464,.015,
-.016759,.014368,
-.016939,.013695,
-.017,.013,
-.017,-.013,
-.016939,-.013695,
-.016759,-.014368,
-.016464,-.015,
-.016064,-.015571,
-.015571,-.016064,
-.015,-.016464,
-.014368,-.016759,
-.013695,-.016939,
-.013,-.017,
.013,-.017,
.013695,-.016939,
.014368,-.016759,
.015,-.016464,
.015571,-.016064,
.016064,-.015571,
.016464,-.015,
.016759,-.014368,
.016939,-.013695,
.017,-.013,
0.0*
%
%ADD44MACRO44*%
%AMMACRO81*
4,1,6,.0135,-.005,
.0065,-.005,
-.0135,-.025,
-.0135,.025,
.0065,.005,
.0135,.005,
.0135,-.005,
0.0*
%
%ADD81MACRO81*%
%AMMACRO117*
4,1,20,.1075,.0635,
.1075,.049,
.118,.049,
.118,.0395,
.1075,.0395,
.1075,-.0395,
.118,-.0395,
.118,-.049,
.1075,-.049,
.1075,-.0635,
-.1075,-.0635,
-.1075,-.049,
-.118,-.049,
-.118,-.0395,
-.1075,-.0395,
-.1075,.0395,
-.118,.0395,
-.118,.049,
-.1075,.049,
-.1075,.0635,
.1075,.0635,
0.0*
%
%ADD117MACRO117*%
%AMMACRO51*
4,1,40,.012,-.008,
.012,.008,
.011939,.008695,
.011759,.009368,
.011464,.01,
.011064,.010571,
.010571,.011064,
.01,.011464,
.009368,.011759,
.008695,.011939,
.008,.012,
-.008,.012,
-.008695,.011939,
-.009368,.011759,
-.01,.011464,
-.010571,.011064,
-.011064,.010571,
-.011464,.01,
-.011759,.009368,
-.011939,.008695,
-.012,.008,
-.012,-.008,
-.011939,-.008695,
-.011759,-.009368,
-.011464,-.01,
-.011064,-.010571,
-.010571,-.011064,
-.01,-.011464,
-.009368,-.011759,
-.008695,-.011939,
-.008,-.012,
.008,-.012,
.008695,-.011939,
.009368,-.011759,
.01,-.011464,
.010571,-.011064,
.011064,-.010571,
.011464,-.01,
.011759,-.009368,
.011939,-.008695,
.012,-.008,
0.0*
%
%ADD51MACRO51*%
%AMMACRO31*
4,1,40,-.008,-.012,
.008,-.012,
.008695,-.011939,
.009368,-.011759,
.01,-.011464,
.010571,-.011064,
.011064,-.010571,
.011464,-.01,
.011759,-.009368,
.011939,-.008695,
.012,-.008,
.012,.008,
.011939,.008695,
.011759,.009368,
.011464,.01,
.011064,.010571,
.010571,.011064,
.01,.011464,
.009368,.011759,
.008695,.011939,
.008,.012,
-.008,.012,
-.008695,.011939,
-.009368,.011759,
-.01,.011464,
-.010571,.011064,
-.011064,.010571,
-.011464,.01,
-.011759,.009368,
-.011939,.008695,
-.012,.008,
-.012,-.008,
-.011939,-.008695,
-.011759,-.009368,
-.011464,-.01,
-.011064,-.010571,
-.010571,-.011064,
-.01,-.011464,
-.009368,-.011759,
-.008695,-.011939,
-.008,-.012,
0.0*
%
%ADD31MACRO31*%
%AMMACRO17*
4,1,40,-.007,-.011,
.007,-.011,
.007695,-.010939,
.008368,-.010759,
.009,-.010464,
.009571,-.010064,
.010064,-.009571,
.010464,-.009,
.010759,-.008368,
.010939,-.007695,
.011,-.007,
.011,.007,
.010939,.007695,
.010759,.008368,
.010464,.009,
.010064,.009571,
.009571,.010064,
.009,.010464,
.008368,.010759,
.007695,.010939,
.007,.011,
-.007,.011,
-.007695,.010939,
-.008368,.010759,
-.009,.010464,
-.009571,.010064,
-.010064,.009571,
-.010464,.009,
-.010759,.008368,
-.010939,.007695,
-.011,.007,
-.011,-.007,
-.010939,-.007695,
-.010759,-.008368,
-.010464,-.009,
-.010064,-.009571,
-.009571,-.010064,
-.009,-.010464,
-.008368,-.010759,
-.007695,-.010939,
-.007,-.011,
0.0*
%
%ADD17MACRO17*%
%AMMACRO35*
4,1,40,-.011,.007,
-.011,-.007,
-.010939,-.007695,
-.010759,-.008368,
-.010464,-.009,
-.010064,-.009571,
-.009571,-.010064,
-.009,-.010464,
-.008368,-.010759,
-.007695,-.010939,
-.007,-.011,
.007,-.011,
.007695,-.010939,
.008368,-.010759,
.009,-.010464,
.009571,-.010064,
.010064,-.009571,
.010464,-.009,
.010759,-.008368,
.010939,-.007695,
.011,-.007,
.011,.007,
.010939,.007695,
.010759,.008368,
.010464,.009,
.010064,.009571,
.009571,.010064,
.009,.010464,
.008368,.010759,
.007695,.010939,
.007,.011,
-.007,.011,
-.007695,.010939,
-.008368,.010759,
-.009,.010464,
-.009571,.010064,
-.010064,.009571,
-.010464,.009,
-.010759,.008368,
-.010939,.007695,
-.011,.007,
0.0*
%
%ADD35MACRO35*%
%ADD181C,.006*%
G75*
%LPD*%
G75*
G36*
G01X24135Y307086D02*
Y328678D01*
X13899D01*
Y307086D01*
X24135D01*
G37*
G36*
G01X13899Y346903D02*
Y387753D01*
X24135D01*
Y377528D01*
X22153D01*
G03Y368928I-933J-4300D01*
G01X24135D01*
Y346903D01*
X13899D01*
G37*
G36*
G01X24135Y405953D02*
Y418778D01*
X41143D01*
Y427086D01*
X13899D01*
Y405953D01*
X24135D01*
G37*
G36*
G01X35342Y307086D02*
Y323622D01*
X26735D01*
Y307086D01*
X35342D01*
G37*
G36*
G01X57756D02*
Y323622D01*
X49149D01*
Y307086D01*
X57756D01*
G37*
G36*
G01X46549D02*
Y323622D01*
X37942D01*
Y307086D01*
X46549D01*
G37*
G36*
G01X68963D02*
Y323622D01*
X60356D01*
Y307086D01*
X68963D01*
G37*
G36*
G01X91377D02*
Y323622D01*
X82770D01*
Y307086D01*
X91377D01*
G37*
G36*
G01X80170D02*
Y323622D01*
X71563D01*
Y307086D01*
X80170D01*
G37*
G36*
G01X93975Y405978D02*
Y418778D01*
X75393D01*
Y427086D01*
X104211D01*
Y405978D01*
X93975D01*
G37*
G36*
G01X104211Y307086D02*
Y328678D01*
X93975D01*
Y307086D01*
X104211D01*
G37*
G36*
G01X93975Y346903D02*
Y368928D01*
X95957D01*
G03Y377528I933J4300D01*
G01X93975D01*
Y387728D01*
X104211D01*
Y346903D01*
X93975D01*
G37*
G36*
G01X187599Y1023622D02*
X107677D01*
Y1001610D01*
X187599D01*
Y1023622D01*
G37*
G36*
G01X241650Y898315D02*
X250200D01*
Y907265D01*
X241650D01*
Y898315D01*
G37*
G36*
G01Y909865D02*
X250200D01*
Y918815D01*
X241650D01*
Y909865D01*
G37*
G36*
G01X252800Y898315D02*
X261350D01*
Y907265D01*
X252800D01*
Y898315D01*
G37*
G36*
G01Y909865D02*
X261350D01*
Y918815D01*
X252800D01*
Y909865D01*
G37*
G36*
G01X597048Y1023622D02*
X265158D01*
Y1001610D01*
X597048D01*
Y1023622D01*
G37*
G36*
G01X797048D02*
X717126D01*
Y1001610D01*
X797048D01*
Y1023622D01*
G37*
G36*
G01X1051200Y244135D02*
X1042650D01*
Y235185D01*
X1051200D01*
Y244135D01*
G37*
G36*
G01Y255685D02*
X1042650D01*
Y246735D01*
X1051200D01*
Y255685D01*
G37*
G36*
G01X1062350Y244135D02*
X1053800D01*
Y235185D01*
X1062350D01*
Y244135D01*
G37*
G36*
G01Y255685D02*
X1053800D01*
Y246735D01*
X1062350D01*
Y255685D01*
G37*
G54D100*
G01X-245081Y-422119D02*
G02I-12000J0D01*
G01X-250231D02*
G02I-6850J0D01*
G01X-241081D02*
X-273081D01*
G01X-257081Y-438119D02*
Y-406119D01*
G01X-241081Y-438119D02*
Y-518119D01*
G01D02*
X1034819D01*
G01X-241081Y-473619D02*
X1034819D01*
G01X-241081Y-438119D02*
X1034819D01*
G01X247319D02*
Y-518119D01*
G01X384819Y-438119D02*
Y-518119D01*
G01X499819Y-438119D02*
Y-518119D01*
G01X667319Y-438119D02*
Y-518119D01*
G01X837319Y-438119D02*
Y-518119D01*
G01X1034819Y-438119D02*
Y-518119D01*
G01X1066819Y-422119D02*
X1034819D01*
G01X1050819Y-438119D02*
Y-406119D01*
G01X1062819Y-422119D02*
G02I-12000J0D01*
G01X1057669D02*
G02I-6850J0D01*
X410826Y332086D03*
Y328149D03*
Y324212D03*
X406889Y332086D03*
Y328149D03*
Y324212D03*
X402952Y332086D03*
Y328149D03*
X410826Y414764D03*
X406889D03*
X402952D03*
X410826Y422638D03*
Y418701D03*
X406889Y422638D03*
Y418701D03*
X402952D03*
X493504Y332086D03*
Y328149D03*
Y324212D03*
Y414764D03*
Y422638D03*
Y418701D03*
X501378Y332086D03*
Y328149D03*
X497441Y332086D03*
Y328149D03*
Y324212D03*
X501378Y414764D03*
X497441D03*
X501378Y418701D03*
X497441Y422638D03*
Y418701D03*
G54D101*
X410826Y336023D03*
X406889D03*
X402952D03*
X410826Y351771D03*
Y347834D03*
Y343897D03*
Y339960D03*
X406889Y351771D03*
Y347834D03*
Y343897D03*
Y339960D03*
X402952Y351771D03*
Y347834D03*
Y343897D03*
Y339960D03*
X410826Y367519D03*
Y363582D03*
Y359645D03*
Y355708D03*
X406889Y367519D03*
Y363582D03*
Y359645D03*
Y355708D03*
X402952Y367519D03*
Y363582D03*
Y359645D03*
Y355708D03*
X410826Y383268D03*
Y379331D03*
Y375394D03*
Y371456D03*
X406889Y383268D03*
Y379331D03*
Y375394D03*
Y371456D03*
X402952Y383268D03*
Y379331D03*
Y375394D03*
Y371456D03*
X410826Y399016D03*
Y395079D03*
Y391142D03*
Y387205D03*
X406889Y399016D03*
Y395079D03*
Y391142D03*
Y387205D03*
X402952Y399016D03*
Y395079D03*
Y391142D03*
Y387205D03*
X410826Y410827D03*
Y406890D03*
Y402953D03*
X406889Y410827D03*
Y406890D03*
Y402953D03*
X402952Y410827D03*
Y406890D03*
Y402953D03*
X426574Y336023D03*
Y332086D03*
Y328149D03*
Y324212D03*
X422637Y336023D03*
Y332086D03*
Y328149D03*
Y324212D03*
X418700Y336023D03*
Y332086D03*
Y328149D03*
Y324212D03*
X414763Y336023D03*
Y332086D03*
Y328149D03*
Y324212D03*
X426574Y351771D03*
Y347834D03*
Y343897D03*
Y339960D03*
X422637Y351771D03*
Y347834D03*
Y343897D03*
Y339960D03*
X418700Y351771D03*
Y347834D03*
Y343897D03*
Y339960D03*
X414763Y351771D03*
Y347834D03*
Y343897D03*
Y339960D03*
X426574Y367519D03*
Y363582D03*
Y359645D03*
Y355708D03*
X422637Y367519D03*
Y363582D03*
Y359645D03*
Y355708D03*
X418700Y367519D03*
Y363582D03*
Y359645D03*
Y355708D03*
X414763Y367519D03*
Y363582D03*
Y359645D03*
Y355708D03*
X426574Y383268D03*
Y379331D03*
Y375394D03*
Y371456D03*
X422637Y383268D03*
Y379331D03*
Y375394D03*
Y371456D03*
X418700Y383268D03*
Y379331D03*
Y375394D03*
Y371456D03*
X414763Y383268D03*
Y379331D03*
Y375394D03*
Y371456D03*
X426574Y399016D03*
Y395079D03*
Y391142D03*
Y387205D03*
X422637Y399016D03*
Y395079D03*
Y391142D03*
Y387205D03*
X418700Y399016D03*
Y395079D03*
Y391142D03*
Y387205D03*
X414763Y399016D03*
Y395079D03*
Y391142D03*
Y387205D03*
X426574Y414764D03*
Y410827D03*
Y406890D03*
Y402953D03*
X422637Y414764D03*
Y410827D03*
Y406890D03*
Y402953D03*
X418700Y414764D03*
Y410827D03*
Y406890D03*
Y402953D03*
X414763Y414764D03*
Y410827D03*
Y406890D03*
Y402953D03*
X426574Y422638D03*
Y418701D03*
X422637Y422638D03*
Y418701D03*
X418700Y422638D03*
Y418701D03*
X414763Y422638D03*
Y418701D03*
X442322Y336023D03*
Y332086D03*
Y328149D03*
Y324212D03*
X438385Y336023D03*
Y332086D03*
Y328149D03*
Y324212D03*
X434448Y336023D03*
Y332086D03*
Y328149D03*
Y324212D03*
X430511Y336023D03*
Y332086D03*
Y328149D03*
Y324212D03*
X442322Y351771D03*
Y347834D03*
Y343897D03*
Y339960D03*
X438385Y351771D03*
Y347834D03*
Y343897D03*
Y339960D03*
X434448Y351771D03*
Y347834D03*
Y343897D03*
Y339960D03*
X430511Y351771D03*
Y347834D03*
Y343897D03*
Y339960D03*
X442322Y367519D03*
Y363582D03*
Y359645D03*
Y355708D03*
X438385Y367519D03*
Y363582D03*
Y359645D03*
Y355708D03*
X434448Y367519D03*
Y363582D03*
Y359645D03*
Y355708D03*
X430511Y367519D03*
Y363582D03*
Y359645D03*
Y355708D03*
X442322Y383268D03*
Y379331D03*
Y375394D03*
Y371456D03*
X438385Y383268D03*
Y379331D03*
Y375394D03*
Y371456D03*
X434448Y383268D03*
Y379331D03*
Y375394D03*
Y371456D03*
X430511Y383268D03*
Y379331D03*
Y375394D03*
Y371456D03*
X442322Y399016D03*
Y395079D03*
Y391142D03*
Y387205D03*
X438385Y399016D03*
Y395079D03*
Y391142D03*
Y387205D03*
X434448Y399016D03*
Y395079D03*
Y391142D03*
Y387205D03*
X430511Y399016D03*
Y395079D03*
Y391142D03*
Y387205D03*
X442322Y414764D03*
Y410827D03*
Y406890D03*
Y402953D03*
X438385Y414764D03*
Y410827D03*
Y406890D03*
Y402953D03*
X434448Y414764D03*
Y410827D03*
Y406890D03*
Y402953D03*
X430511Y414764D03*
Y410827D03*
Y406890D03*
Y402953D03*
X442322Y422638D03*
Y418701D03*
X438385Y422638D03*
Y418701D03*
X434448Y422638D03*
Y418701D03*
X430511Y422638D03*
Y418701D03*
X458071Y336023D03*
Y332086D03*
Y328149D03*
Y324212D03*
X454134Y336023D03*
Y332086D03*
Y328149D03*
Y324212D03*
X450196Y336023D03*
Y332086D03*
Y328149D03*
Y324212D03*
X446259Y336023D03*
Y332086D03*
Y328149D03*
Y324212D03*
X458071Y351771D03*
Y347834D03*
Y343897D03*
Y339960D03*
X454134Y351771D03*
Y347834D03*
Y343897D03*
Y339960D03*
X450196Y351771D03*
Y347834D03*
Y343897D03*
Y339960D03*
X446259Y351771D03*
Y347834D03*
Y343897D03*
Y339960D03*
X458071Y367519D03*
Y363582D03*
Y359645D03*
Y355708D03*
X454134Y367519D03*
Y363582D03*
Y359645D03*
Y355708D03*
X450196Y367519D03*
Y363582D03*
Y359645D03*
Y355708D03*
X446259Y367519D03*
Y363582D03*
Y359645D03*
Y355708D03*
X458071Y383268D03*
Y379331D03*
Y375394D03*
Y371456D03*
X454134Y383268D03*
Y379331D03*
Y375394D03*
Y371456D03*
X450196Y383268D03*
Y379331D03*
Y375394D03*
Y371456D03*
X446259Y383268D03*
Y379331D03*
Y375394D03*
Y371456D03*
X458071Y399016D03*
Y395079D03*
Y391142D03*
Y387205D03*
X454134Y399016D03*
Y395079D03*
Y391142D03*
Y387205D03*
X450196Y399016D03*
Y395079D03*
Y391142D03*
Y387205D03*
X446259Y399016D03*
Y395079D03*
Y391142D03*
Y387205D03*
X458071Y414764D03*
Y410827D03*
Y406890D03*
Y402953D03*
X454134Y414764D03*
Y410827D03*
Y406890D03*
Y402953D03*
X450196Y414764D03*
Y410827D03*
Y406890D03*
Y402953D03*
X446259Y414764D03*
Y410827D03*
Y406890D03*
Y402953D03*
X458071Y422638D03*
Y418701D03*
X454134Y422638D03*
Y418701D03*
X450196Y422638D03*
Y418701D03*
X446259Y422638D03*
Y418701D03*
X477756Y336023D03*
Y332086D03*
Y328149D03*
Y324212D03*
X473819Y336023D03*
Y332086D03*
Y328149D03*
Y324212D03*
X469882Y336023D03*
Y332086D03*
Y328149D03*
Y324212D03*
X465945Y336023D03*
Y332086D03*
Y328149D03*
Y324212D03*
X462008Y336023D03*
Y332086D03*
Y328149D03*
Y324212D03*
X477756Y351771D03*
Y347834D03*
Y343897D03*
Y339960D03*
X473819Y351771D03*
Y347834D03*
Y343897D03*
Y339960D03*
X469882Y351771D03*
Y347834D03*
Y343897D03*
Y339960D03*
X465945Y351771D03*
Y347834D03*
Y343897D03*
Y339960D03*
X462008Y351771D03*
Y347834D03*
Y343897D03*
Y339960D03*
X477756Y367519D03*
Y363582D03*
Y359645D03*
Y355708D03*
X473819Y367519D03*
Y363582D03*
Y359645D03*
Y355708D03*
X469882Y367519D03*
Y363582D03*
Y359645D03*
Y355708D03*
X465945Y367519D03*
Y363582D03*
Y359645D03*
Y355708D03*
X462008Y367519D03*
Y363582D03*
Y359645D03*
Y355708D03*
X477756Y383268D03*
Y379331D03*
Y375394D03*
Y371456D03*
X473819Y383268D03*
Y379331D03*
Y375394D03*
Y371456D03*
X469882Y383268D03*
Y379331D03*
Y375394D03*
Y371456D03*
X465945Y383268D03*
Y379331D03*
Y375394D03*
Y371456D03*
X462008Y383268D03*
Y379331D03*
Y375394D03*
Y371456D03*
X477756Y399016D03*
Y395079D03*
Y391142D03*
Y387205D03*
X473819Y399016D03*
Y395079D03*
Y391142D03*
Y387205D03*
X469882Y399016D03*
Y395079D03*
Y391142D03*
Y387205D03*
X465945Y399016D03*
Y395079D03*
Y391142D03*
Y387205D03*
X462008Y399016D03*
Y395079D03*
Y391142D03*
Y387205D03*
X477756Y414764D03*
Y410827D03*
Y406890D03*
Y402953D03*
X473819Y414764D03*
Y410827D03*
Y406890D03*
Y402953D03*
X469882Y414764D03*
Y410827D03*
Y406890D03*
Y402953D03*
X465945Y414764D03*
Y410827D03*
Y406890D03*
Y402953D03*
X462008Y414764D03*
Y410827D03*
Y406890D03*
Y402953D03*
X477756Y422638D03*
Y418701D03*
X473819Y422638D03*
Y418701D03*
X469882Y422638D03*
Y418701D03*
X465945Y422638D03*
Y418701D03*
X462008Y422638D03*
Y418701D03*
X493504Y336023D03*
X489567D03*
Y332086D03*
Y328149D03*
Y324212D03*
X485630Y336023D03*
Y332086D03*
Y328149D03*
Y324212D03*
X481693Y336023D03*
Y332086D03*
Y328149D03*
Y324212D03*
X493504Y351771D03*
Y347834D03*
Y343897D03*
Y339960D03*
X489567Y351771D03*
Y347834D03*
Y343897D03*
Y339960D03*
X485630Y351771D03*
Y347834D03*
Y343897D03*
Y339960D03*
X481693Y351771D03*
Y347834D03*
Y343897D03*
Y339960D03*
X493504Y367519D03*
Y363582D03*
Y359645D03*
Y355708D03*
X489567Y367519D03*
Y363582D03*
Y359645D03*
Y355708D03*
X485630Y367519D03*
Y363582D03*
Y359645D03*
Y355708D03*
X481693Y367519D03*
Y363582D03*
Y359645D03*
Y355708D03*
X493504Y383268D03*
Y379331D03*
Y375394D03*
Y371456D03*
X489567Y383268D03*
Y379331D03*
Y375394D03*
Y371456D03*
X485630Y383268D03*
Y379331D03*
Y375394D03*
Y371456D03*
X481693Y383268D03*
Y379331D03*
Y375394D03*
Y371456D03*
X493504Y399016D03*
Y395079D03*
Y391142D03*
Y387205D03*
X489567Y399016D03*
Y395079D03*
Y391142D03*
Y387205D03*
X485630Y399016D03*
Y395079D03*
Y391142D03*
Y387205D03*
X481693Y399016D03*
Y395079D03*
Y391142D03*
Y387205D03*
X493504Y410827D03*
Y406890D03*
Y402953D03*
X489567Y414764D03*
Y410827D03*
Y406890D03*
Y402953D03*
X485630Y414764D03*
Y410827D03*
Y406890D03*
Y402953D03*
X481693Y414764D03*
Y410827D03*
Y406890D03*
Y402953D03*
X489567Y422638D03*
Y418701D03*
X485630Y422638D03*
Y418701D03*
X481693Y422638D03*
Y418701D03*
X501378Y336023D03*
X497441D03*
X501378Y351771D03*
Y347834D03*
Y343897D03*
Y339960D03*
X497441Y351771D03*
Y347834D03*
Y343897D03*
Y339960D03*
X501378Y367519D03*
Y363582D03*
Y359645D03*
Y355708D03*
X497441Y367519D03*
Y363582D03*
Y359645D03*
Y355708D03*
X501378Y383268D03*
Y379331D03*
Y375394D03*
Y371456D03*
X497441Y383268D03*
Y379331D03*
Y375394D03*
Y371456D03*
X501378Y399016D03*
Y395079D03*
Y391142D03*
Y387205D03*
X497441Y399016D03*
Y395079D03*
Y391142D03*
Y387205D03*
X501378Y410827D03*
Y406890D03*
Y402953D03*
X497441Y410827D03*
Y406890D03*
Y402953D03*
G54D110*
X599941Y70118D03*
X607933D03*
X595905Y80118D03*
X603897D03*
X611889D03*
X615925Y70118D03*
X623917D03*
X627953Y80118D03*
X631909Y70118D03*
X639901D03*
X635945Y80118D03*
X643937D03*
G54D102*
X444177Y299000D03*
Y291000D03*
X452977Y295000D03*
G54D111*
X629000Y333600D03*
Y358400D03*
X649500Y333600D03*
Y358400D03*
G54D120*
X707716Y110457D03*
Y132111D03*
X735716Y110457D03*
Y132111D03*
X780668Y448125D03*
Y454031D03*
X792880Y448125D03*
Y454031D03*
X1348106Y433547D03*
X1335894D03*
X1348106Y439453D03*
X1335894D03*
G54D10*
X19272Y337795D03*
Y396850D03*
X98838Y337795D03*
Y396850D03*
G54D103*
X479923Y298683D03*
Y306883D03*
X494123Y298683D03*
Y306883D03*
G54D130*
X751484Y548491D03*
Y553491D03*
Y558491D03*
Y563491D03*
X771484Y548491D03*
Y563491D03*
Y558491D03*
Y553491D03*
X997274Y199578D03*
Y204578D03*
Y209578D03*
Y214578D03*
X1017274Y204578D03*
Y199578D03*
Y214578D03*
Y209578D03*
X1159934Y599672D03*
Y604672D03*
Y609672D03*
Y614672D03*
X1179934D03*
Y609672D03*
Y604672D03*
Y599672D03*
X1255000Y583000D03*
Y588000D03*
Y593000D03*
Y598000D03*
X1275000Y583000D03*
Y598000D03*
Y593000D03*
Y588000D03*
X1287372Y301500D03*
Y296500D03*
Y291500D03*
Y306500D03*
X1314872Y291500D03*
Y296500D03*
Y301500D03*
Y306500D03*
G54D121*
X708216Y112426D03*
Y114394D03*
Y116363D03*
Y118331D03*
Y120300D03*
Y122268D03*
Y124237D03*
Y126205D03*
Y128174D03*
Y130142D03*
X735216Y122268D03*
Y120300D03*
Y118331D03*
Y116363D03*
Y114394D03*
Y112426D03*
Y130142D03*
Y128174D03*
Y126205D03*
Y124237D03*
G54D112*
X639300Y612460D03*
Y609900D03*
Y607340D03*
X646700D03*
Y609900D03*
Y612460D03*
X866200Y636940D03*
Y639500D03*
Y642060D03*
X858800D03*
Y639500D03*
Y636940D03*
G54D122*
X698818Y764644D03*
Y767204D03*
Y769764D03*
Y772324D03*
X696818Y800144D03*
Y802704D03*
Y805264D03*
Y807824D03*
X715118Y772324D03*
Y769764D03*
Y767204D03*
Y764644D03*
X713118Y807824D03*
Y805264D03*
Y802704D03*
Y800144D03*
G54D140*
X837031Y396460D03*
Y399019D03*
Y401578D03*
Y404137D03*
Y406696D03*
X856517Y401578D03*
Y399019D03*
Y396460D03*
Y406696D03*
Y404137D03*
X1106725Y865166D03*
Y867725D03*
Y870284D03*
Y872843D03*
Y875402D03*
X1126211D03*
Y872843D03*
Y870284D03*
Y867725D03*
Y865166D03*
G54D104*
X543699Y168150D03*
X541729D03*
X539759D03*
X537789D03*
X535824D03*
X533854D03*
Y243850D03*
X535824D03*
X537789D03*
X539759D03*
X541729D03*
X543699D03*
X559444Y168150D03*
X557474D03*
X555509D03*
X553539D03*
X551569D03*
X549604D03*
X547634D03*
X545664D03*
Y243850D03*
X547634D03*
X549604D03*
X551569D03*
X553539D03*
X555509D03*
X557474D03*
X559444D03*
X575194Y168150D03*
X573224D03*
X571254D03*
X569289D03*
X567319D03*
X565349D03*
X563384D03*
X561414D03*
Y243850D03*
X563384D03*
X565349D03*
X567319D03*
X569289D03*
X571254D03*
X573224D03*
X575194D03*
X587004Y168150D03*
X585034D03*
X583069D03*
X581099D03*
X579129D03*
X577159D03*
Y243850D03*
X579129D03*
X581099D03*
X583069D03*
X585034D03*
X587004D03*
X1311403Y874634D03*
X1309438D03*
X1307468D03*
X1305498D03*
X1303533D03*
Y890934D03*
X1305498D03*
X1307468D03*
X1309438D03*
X1311403D03*
X1331438Y643634D03*
X1329468D03*
X1327498D03*
X1325533D03*
Y659934D03*
X1327498D03*
X1329468D03*
X1331438D03*
X1333403Y643634D03*
Y659934D03*
G54D113*
X655750Y462500D03*
G54D20*
X25500Y836000D03*
X32304Y834720D03*
X30500Y855000D03*
X28790Y880734D03*
X25304Y899220D03*
X29804Y904220D03*
X51304Y875720D03*
X51043Y889981D03*
X42000Y884000D03*
X36054Y910720D03*
X66860Y648370D03*
X67304Y715720D03*
X62804Y722720D03*
X55304Y742720D03*
X60804Y843720D03*
X56304Y888720D03*
X63304Y882220D03*
X80926Y644426D03*
X74500Y644000D03*
X69500Y642500D03*
X76000Y652500D03*
X70500Y651500D03*
X79500Y656500D03*
X82000Y650500D03*
X81304Y722220D03*
X78304Y759720D03*
X71804Y801720D03*
X80304Y847220D03*
X70304Y889720D03*
X98304Y721720D03*
X93347Y722263D03*
X90304Y766720D03*
X100104Y793820D03*
X96704Y809720D03*
X96404Y797320D03*
X96804Y840720D03*
X96304Y846720D03*
X93043Y883220D03*
X90488Y888720D03*
X85495Y892029D03*
X95603Y890421D03*
X116000Y628000D03*
X111500Y618500D03*
X106500Y630500D03*
X112000Y636000D03*
X103804Y755720D03*
X106004Y886970D03*
X123406Y327453D03*
X121000Y612500D03*
X133500Y618500D03*
X119500Y621000D03*
X133500Y657500D03*
X130000Y678500D03*
X134000Y686500D03*
X131204Y789970D03*
X133004Y802520D03*
X133104Y807420D03*
X133174Y796750D03*
X141500Y615000D03*
X150000Y650500D03*
X145000Y792000D03*
X149250Y851750D03*
X148500Y884500D03*
X164300Y453800D03*
X159200Y470300D03*
X159500Y475500D03*
X161805Y525750D03*
X154500Y686500D03*
X176400Y454200D03*
X169500Y462800D03*
X175900Y463000D03*
X182800Y474800D03*
X177555Y530000D03*
X169555D03*
X171500Y681500D03*
X179500Y843500D03*
X175000Y861000D03*
X195800Y530000D03*
X188955Y534100D03*
X193115Y545060D03*
X195555Y558060D03*
X186000Y818000D03*
X199750Y864750D03*
X208000Y506500D03*
X215153Y521183D03*
X215055Y556500D03*
X214555Y564000D03*
X211500Y842000D03*
X204500Y842500D03*
X204000Y850000D03*
X200016Y859484D03*
X205000Y856000D03*
X203500Y878500D03*
X212500Y876000D03*
X204500Y868500D03*
X216000Y879500D03*
X208000Y925500D03*
X224148Y577400D03*
X221805Y569750D03*
X217000Y807500D03*
X218500Y839500D03*
X228890Y838890D03*
X224000Y838500D03*
X221016Y876984D03*
X228500Y895000D03*
X230000Y879500D03*
X226000Y900000D03*
X245000Y427000D03*
X234000Y558500D03*
X235000Y839000D03*
X239000Y853000D03*
X240000Y858500D03*
X239500Y847500D03*
X235500Y875500D03*
X237000Y919900D03*
X254500Y184000D03*
X261500Y203000D03*
X250500Y419000D03*
X264500Y422078D03*
X264409Y439354D03*
X263000Y879000D03*
X265000Y893000D03*
X277000Y194500D03*
X271500Y888500D03*
X281000Y882500D03*
X277500Y902800D03*
X287929Y356500D03*
X311500Y71500D03*
X310000Y84500D03*
X302000Y97500D03*
X306429Y310000D03*
X312929Y382000D03*
X299055Y419500D03*
X330000Y90500D03*
X315000Y89000D03*
X317147Y93294D03*
X326555Y425500D03*
X325224Y455669D03*
X329055Y548500D03*
X347500Y66000D03*
X343000Y77500D03*
X337000Y90500D03*
X342429Y327500D03*
X346500Y341500D03*
X347055Y468450D03*
X336055Y552000D03*
X339888Y611888D03*
X340500Y873600D03*
X335500Y881500D03*
X338000Y907000D03*
X341000Y902500D03*
X336000Y899500D03*
X340300Y948500D03*
X360200Y77400D03*
X357429Y237500D03*
X352929Y242000D03*
X361929D03*
X347929Y321500D03*
X353429Y344000D03*
X351555Y465480D03*
X354988Y456325D03*
X350055Y484623D03*
X351055Y550500D03*
X361500Y880500D03*
X358500Y884500D03*
X360900Y890100D03*
X362780Y895220D03*
X361178Y991000D03*
X375429Y237500D03*
X366429Y238000D03*
X370929Y242000D03*
X378429D03*
X374000Y392500D03*
X369500Y401000D03*
X370155Y463000D03*
X366500Y549500D03*
X373000Y915000D03*
X374018Y991000D03*
X381000Y63500D03*
X381429Y237500D03*
X386500D03*
X384500Y243000D03*
X388055Y307500D03*
X384055Y311500D03*
Y317000D03*
X392555Y309500D03*
X386555Y333000D03*
X384000Y323000D03*
X388829Y328323D03*
X384055Y339500D03*
X383555Y353000D03*
X385055Y347500D03*
X384055Y371000D03*
X380500Y393000D03*
X385023Y387783D03*
X388023Y412283D03*
X391000Y417500D03*
X383555Y403000D03*
X382500Y413000D03*
X384504Y408000D03*
X387555Y459700D03*
X394155Y460000D03*
X390555Y455500D03*
X395000Y877500D03*
X389000D03*
X380500Y915000D03*
X397500Y249000D03*
X410400Y242116D03*
X401429Y244400D03*
X402800Y282700D03*
X399755Y295700D03*
X409000Y295500D03*
X404000Y290500D03*
X406055Y307500D03*
X401555Y309500D03*
X411555D03*
X397055Y307500D03*
X398000Y885000D03*
X411500Y893000D03*
X406000Y895500D03*
X411000Y898500D03*
X407500Y903775D03*
X398500Y908000D03*
X427000Y111000D03*
X424500Y116000D03*
X423500Y122000D03*
X428375Y122635D03*
X415100Y235900D03*
X417970Y231884D03*
X416200Y245300D03*
X429429Y252900D03*
X425000Y245500D03*
X419205Y240000D03*
X426555Y271500D03*
X418755Y290000D03*
X426470Y299463D03*
X416555Y307500D03*
X425755Y309800D03*
X429355Y306100D03*
X438429Y100500D03*
X440000Y115000D03*
X434209Y232474D03*
X434000Y244500D03*
X438000Y300500D03*
X433500Y297500D03*
X439055Y309900D03*
X445855Y309200D03*
X437155Y305300D03*
X442155Y306000D03*
X432955Y309700D03*
X446500Y120500D03*
X459283Y169140D03*
X461500Y157000D03*
X457934Y164526D03*
X458929Y180500D03*
X458529Y189761D03*
X457500Y199500D03*
X461000Y215000D03*
X461500Y224500D03*
X457500Y269400D03*
X456170Y281419D03*
X459000Y302000D03*
X453500Y303500D03*
X448000Y304500D03*
X452055Y308500D03*
X457055Y308000D03*
X460055Y312000D03*
X463000Y117500D03*
X465500Y122500D03*
X466000Y137000D03*
X462429Y133500D03*
X466000Y130000D03*
X462500Y126500D03*
X463500Y141500D03*
X466500Y155500D03*
X466000Y176500D03*
X465055Y313500D03*
X511200Y412600D03*
X511255Y420200D03*
X524635Y212188D03*
X537500Y154750D03*
X538500Y160000D03*
X543600Y161020D03*
X556500Y158500D03*
X552000Y161000D03*
X560355Y333600D03*
X559555Y362500D03*
X553055Y364500D03*
X567429Y159500D03*
X572629D03*
X562231Y159650D03*
X592500Y205000D03*
Y217500D03*
X593000Y212500D03*
X592500Y223000D03*
X597000Y196500D03*
X618950Y597000D03*
X638100Y462500D03*
X632000Y571000D03*
X631000Y603000D03*
X631500Y617000D03*
X655751Y448519D03*
X644000Y453000D03*
X653955Y594955D03*
X654500Y602500D03*
Y617000D03*
X660500Y440000D03*
X659462Y475500D03*
X670000Y476500D03*
X663962Y473500D03*
X681748Y134000D03*
X686718Y793718D03*
X690000Y810500D03*
X699500Y56775D03*
X695000Y63500D03*
X699000Y72500D03*
X698000Y80500D03*
X702473Y87000D03*
X704933Y98147D03*
X699716Y137284D03*
X694466Y133282D03*
X700748Y144000D03*
X706822Y141225D03*
X693055Y261500D03*
X692555Y267500D03*
X695500Y460500D03*
X692500Y767204D03*
X694500Y779500D03*
X694750Y884750D03*
X697925Y894425D03*
X724000Y69016D03*
X715940Y71750D03*
X724716Y94784D03*
X710748Y100000D03*
X718448Y100900D03*
X716048Y95900D03*
X709848Y94100D03*
X715748Y143000D03*
X719839Y140488D03*
X723248Y144500D03*
X710748Y144000D03*
X724887Y566963D03*
X718000Y571000D03*
X711000Y758000D03*
X723000Y767204D03*
X721500Y802704D03*
X720500Y797500D03*
X714000Y879000D03*
X731500Y57500D03*
X728500Y61500D03*
X737000Y90000D03*
X734500Y97500D03*
X737500Y145000D03*
X731716Y144984D03*
X740748Y140500D03*
X738748Y189500D03*
X726100Y195600D03*
X729800Y210000D03*
X736377Y894123D03*
X738000Y889000D03*
X730000Y891560D03*
X732500Y899000D03*
X755000Y56500D03*
X754500Y62000D03*
X746500Y105000D03*
X741500Y100500D03*
X748248Y118500D03*
X749500Y110000D03*
X744000Y115500D03*
X755248Y123500D03*
X744000Y157500D03*
Y465500D03*
Y471500D03*
X745000Y553500D03*
X744500Y558500D03*
X744000Y563500D03*
X743000Y587500D03*
X757500Y590000D03*
X751000Y874500D03*
X765500Y83500D03*
X768200Y92800D03*
X769000Y101500D03*
X758748Y137500D03*
X758000Y448500D03*
X763000Y463000D03*
Y467800D03*
X764500Y483000D03*
X771000Y644500D03*
X772250Y672250D03*
X764500Y668000D03*
X774271Y699729D03*
X762000Y874500D03*
X783000Y133500D03*
X778000Y152250D03*
X775000Y455000D03*
X789000Y471500D03*
X784000Y469500D03*
X778000D03*
Y548500D03*
Y553491D03*
X778454Y559445D03*
X787000Y583500D03*
X786500Y648000D03*
X788500Y653000D03*
X785500Y685500D03*
X775500Y717500D03*
X775103Y857397D03*
X775500Y881250D03*
X796000Y430000D03*
X793000Y439500D03*
X800000Y458000D03*
X802000Y466000D03*
X805500Y475078D03*
X794000Y737500D03*
X799968Y737000D03*
X818500Y407500D03*
X819000Y451000D03*
X810000Y484078D03*
X823000Y519000D03*
X813000Y743500D03*
X832500Y363500D03*
X830250Y727250D03*
X826500Y776430D03*
Y851500D03*
X828940Y873500D03*
X849500Y429000D03*
X846500Y468000D03*
X853095Y649905D03*
X841000Y715500D03*
X857000Y80500D03*
X872750Y96500D03*
X872500Y338460D03*
X862240D03*
X871820Y353380D03*
X860820D03*
X868500Y390000D03*
X864500Y411000D03*
X861000Y429000D03*
X869250Y471250D03*
X862750Y613750D03*
X869000Y629500D03*
X861000Y680000D03*
X869000Y679000D03*
X860000Y702000D03*
X857500Y715250D03*
X865300Y748000D03*
X879500Y56500D03*
Y67500D03*
X878500Y77000D03*
X880000Y371500D03*
X874500Y449000D03*
X881500Y467500D03*
X876500Y475000D03*
X879060Y642060D03*
X880000Y657500D03*
X877500Y700500D03*
Y705500D03*
X899750Y53250D03*
X920000Y66250D03*
X912250D03*
X939678Y54300D03*
X941000Y59500D03*
X949950Y443200D03*
X943450Y452700D03*
X950950Y458700D03*
X966000Y200500D03*
X961950Y443200D03*
X957068Y458600D03*
X975500Y205000D03*
X982500Y397500D03*
X998000Y80000D03*
X991000Y204578D03*
Y214578D03*
Y209578D03*
X1003750Y475873D03*
X998000Y470500D03*
X994000Y507800D03*
X997900Y503700D03*
X1002200Y506700D03*
X998200Y532300D03*
X1013200Y52600D03*
X1019000Y78500D03*
X1013000Y91500D03*
X1010250Y459346D03*
X1008000Y492000D03*
X1008100Y504000D03*
X1012500Y506500D03*
Y532900D03*
X1018200Y532400D03*
X1004400D03*
X1017000Y545300D03*
X1013000Y554100D03*
X1020500Y862218D03*
X1015500Y876000D03*
Y894500D03*
X1025000Y124500D03*
X1022000Y147500D03*
X1031000Y141000D03*
X1032500Y165000D03*
X1036000Y171000D03*
X1023922Y199578D03*
Y204578D03*
X1023422Y209578D03*
X1032100Y577100D03*
X1028900Y583700D03*
X1027716Y902500D03*
X1045000Y128500D03*
X1039285Y139500D03*
X1051500Y172500D03*
X1051600Y214500D03*
X1041000Y276000D03*
X1051500Y601000D03*
X1050000Y669500D03*
X1051600Y688700D03*
X1038500Y855000D03*
Y914500D03*
X1067500Y222000D03*
X1060500Y275000D03*
X1067900Y485600D03*
X1056000Y673500D03*
X1057300Y694200D03*
X1055900Y703500D03*
X1056000Y708900D03*
X1057776Y699081D03*
X1055400Y714600D03*
X1065688Y746000D03*
X1078000Y141000D03*
X1086000Y167000D03*
X1075800Y204900D03*
X1070500Y229000D03*
X1085900Y644900D03*
X1086200Y656300D03*
X1084900Y690594D03*
X1085992Y707113D03*
X1075289Y738000D03*
X1088000Y220500D03*
X1092200Y258100D03*
X1097000Y423100D03*
X1088000Y450000D03*
X1098500Y449500D03*
X1099600Y643900D03*
X1087200Y664900D03*
X1101534Y650852D03*
X1091300Y650500D03*
X1094500Y678600D03*
X1087000Y676000D03*
X1093600Y670024D03*
X1100900Y694624D03*
X1097000Y686224D03*
X1086800Y696849D03*
X1086700Y682600D03*
X1094800Y691800D03*
X1095000Y712000D03*
X1086324Y702324D03*
X1094449Y698500D03*
X1091000Y705000D03*
X1096500Y717000D03*
X1101500Y718000D03*
X1095900Y722000D03*
X1101100Y723000D03*
X1091299Y719103D03*
X1086500Y719000D03*
X1098000Y810000D03*
X1099550Y838740D03*
X1096218Y859500D03*
X1101700Y854100D03*
X1099000Y877500D03*
X1103200Y259300D03*
X1114900Y641800D03*
X1111824Y648376D03*
X1110000Y642300D03*
X1104500Y643500D03*
X1107274Y650126D03*
X1106500Y718100D03*
X1106200Y723100D03*
X1115200Y745400D03*
X1118000Y739000D03*
X1114450Y735550D03*
X1107500Y801500D03*
X1121500Y257500D03*
X1134000Y266500D03*
Y261500D03*
X1134500Y282284D03*
X1135000Y274500D03*
X1120000Y629500D03*
X1128700Y622000D03*
X1124000Y644500D03*
X1120000Y634500D03*
X1120500Y639500D03*
X1129400Y641300D03*
X1132795Y644695D03*
X1127184Y648612D03*
X1129911Y746600D03*
X1131661Y756839D03*
X1126000Y850534D03*
X1141000Y291750D03*
X1141421Y632142D03*
X1146000Y630700D03*
X1139500Y644500D03*
Y639500D03*
X1145500Y644500D03*
X1150400Y641800D03*
X1135600Y649100D03*
X1140300Y745100D03*
X1141500Y761500D03*
X1139718Y854218D03*
X1154000Y598500D03*
X1163500Y620500D03*
X1155500Y624500D03*
X1163600Y642700D03*
X1152785Y646200D03*
X1156400Y642600D03*
X1157285Y649100D03*
X1157680Y739518D03*
X1153777Y736723D03*
X1156000Y866000D03*
X1179345Y253661D03*
X1179500Y367500D03*
X1183000Y396500D03*
X1173500Y550400D03*
X1173000Y626000D03*
X1180500Y621000D03*
X1182000Y643000D03*
X1182900Y649100D03*
X1183370Y735070D03*
X1178500Y741500D03*
X1182000Y745500D03*
X1172000Y744000D03*
X1175500Y748000D03*
X1172000Y761000D03*
X1188500Y237482D03*
X1199677Y242913D03*
Y251000D03*
X1187000Y255000D03*
X1195677Y257000D03*
X1185000Y367500D03*
X1188000Y396500D03*
X1198500Y396000D03*
X1186500Y604600D03*
X1191500Y631000D03*
X1193500Y626500D03*
X1188000Y634500D03*
X1185500Y639500D03*
X1195000Y643000D03*
X1194000Y637200D03*
X1195500Y776500D03*
X1191500Y807000D03*
X1207500Y235750D03*
X1207700Y244095D03*
X1203000Y645500D03*
X1214000Y642500D03*
X1207869Y643674D03*
X1202500Y638500D03*
X1212000Y685000D03*
X1211000Y696075D03*
X1213000Y712500D03*
X1208500Y710500D03*
X1202000Y709000D03*
X1206500Y706000D03*
X1209500Y701500D03*
X1207000Y715500D03*
X1202500Y727500D03*
X1202000Y720000D03*
X1207000Y720500D03*
X1202000Y715000D03*
X1208000Y727500D03*
X1215500Y723000D03*
X1216000Y741000D03*
X1206040Y732500D03*
X1208000Y738500D03*
X1204500Y769000D03*
X1215500Y800500D03*
X1207688Y800688D03*
X1205100Y855000D03*
X1230500Y431500D03*
X1231500Y439000D03*
X1230500Y643000D03*
X1231000Y665000D03*
X1227500Y651500D03*
X1228000Y673000D03*
X1224750Y692250D03*
X1223500Y709000D03*
X1226500Y767500D03*
X1221016Y840984D03*
X1229500Y831500D03*
X1219100Y855500D03*
X1244000Y200500D03*
X1244997Y238331D03*
X1241000Y235671D03*
X1249000Y230500D03*
X1249649Y225588D03*
X1242000Y243500D03*
X1242636Y248258D03*
X1240377Y255000D03*
Y259843D03*
X1237000Y432000D03*
X1235500Y449000D03*
X1237000Y463500D03*
X1245500Y461700D03*
X1242500Y588000D03*
X1248000Y593000D03*
Y598000D03*
X1242900Y647000D03*
X1238838Y653662D03*
X1238500Y663000D03*
X1246855Y665100D03*
X1243500Y679000D03*
X1239500Y671000D03*
X1239100Y696500D03*
X1240000Y683000D03*
X1246000Y687500D03*
X1244824Y702176D03*
X1246500Y738500D03*
X1236500Y757500D03*
X1241500Y757000D03*
X1237000Y750000D03*
X1246000Y841000D03*
X1238100Y848400D03*
X1261862Y38583D03*
X1261677Y231000D03*
X1261177Y226000D03*
X1264600Y238800D03*
X1265500Y246500D03*
X1265900Y254900D03*
X1252677Y259500D03*
X1252000Y439500D03*
X1263968Y463032D03*
X1253500Y461500D03*
X1252500Y453927D03*
X1254000Y564500D03*
X1265500Y577500D03*
X1253500Y661000D03*
X1266000Y669000D03*
X1258500Y684000D03*
X1269500Y30000D03*
X1267500Y549500D03*
X1278000Y573200D03*
X1277000Y656000D03*
X1282000Y649000D03*
X1280500Y681500D03*
Y674500D03*
X1278815Y668315D03*
X1284000Y30000D03*
X1295500Y26500D03*
X1291000Y425000D03*
X1299000Y429000D03*
X1283225Y579501D03*
X1284825Y631901D03*
X1295500Y656000D03*
X1291000Y735000D03*
X1293000Y862100D03*
X1299500Y865000D03*
X1306500Y38000D03*
X1302500Y455000D03*
X1308617Y568912D03*
X1314500Y642500D03*
X1315500Y650925D03*
X1303500Y655500D03*
X1314500Y679500D03*
X1303784Y794284D03*
X1308784D03*
X1314000Y794000D03*
X1306000Y827000D03*
X1312500D03*
Y862000D03*
X1303070Y909853D03*
X1306968Y898500D03*
X1318500Y37500D03*
Y55000D03*
X1328200Y50000D03*
X1316250Y323250D03*
X1317700Y421000D03*
X1323500Y441500D03*
X1321707Y565252D03*
X1324117Y575512D03*
X1322717Y592412D03*
X1320617Y587312D03*
X1324917Y584912D03*
X1321617Y613812D03*
X1325900Y602100D03*
X1329017Y613012D03*
X1322617Y608912D03*
X1318700Y665800D03*
X1324000Y675000D03*
X1317500Y827000D03*
X1320000Y862000D03*
X1316968Y909984D03*
X1337612Y63000D03*
X1337500Y77000D03*
X1336500Y129000D03*
X1344500Y450500D03*
X1340000Y448000D03*
X1343867Y571200D03*
X1348500Y574500D03*
X1334384Y613278D03*
X1338867Y615534D03*
X1342000Y673000D03*
X1355000Y106000D03*
X1355500Y416500D03*
X1360000Y433500D03*
X1351250Y424500D03*
X1354945Y444400D03*
X1354000Y438700D03*
X1352500Y460500D03*
X1354117Y574912D03*
X1360117D03*
X1350017Y615812D03*
X1355517Y613612D03*
G54D11*
X21220Y373228D03*
X96890D03*
X157480Y283071D03*
X220472D03*
G54D131*
X747750Y698500D03*
X766250D03*
X842218Y691284D03*
X860718D03*
G54D114*
X653250Y462500D03*
G54D141*
X846774Y401578D03*
X1035216Y884468D03*
X1116468Y870284D03*
G54D123*
X706560Y876750D03*
X704000D03*
X701440D03*
Y870250D03*
X706560D03*
X724940Y464572D03*
X730060D03*
Y471072D03*
X727500D03*
X724940D03*
X788060Y871250D03*
X785500D03*
X782940D03*
Y864750D03*
X788060D03*
X1101986Y823344D03*
Y816844D03*
X1107106Y823344D03*
X1104546D03*
X1107106Y816844D03*
X1195940Y862250D03*
X1198500D03*
X1195940Y868750D03*
X1208940Y862250D03*
X1211500D03*
X1214060D03*
X1201060D03*
X1214060Y868750D03*
X1208940D03*
X1201060D03*
X1240660Y840850D03*
X1238100D03*
X1235540D03*
Y834350D03*
X1240660D03*
G54D30*
X39804Y937020D03*
X97500Y936800D03*
X153200Y666200D03*
X179000Y857300D03*
X180000Y911800D03*
X190000D03*
X185000D03*
X212500Y796300D03*
X343000Y73300D03*
X520000Y151800D03*
X687968Y765784D03*
X727968Y763784D03*
X793500Y733300D03*
X809000Y343800D03*
X810000Y479800D03*
X904500Y81800D03*
X1065500Y164300D03*
X1056700Y178800D03*
X1107968Y256584D03*
X1268468Y471584D03*
X1287000Y452800D03*
X1360000Y429300D03*
X1357500Y466300D03*
G54D21*
X34304Y893920D03*
X29804D03*
X25304D03*
X38804D03*
Y901920D03*
X47804Y935920D03*
X58804Y717920D03*
X65804Y843420D03*
X76804Y717920D03*
X77804Y769920D03*
X73804D03*
X74304Y843420D03*
X83304D03*
X78804D03*
X99536Y762926D03*
X96772Y771204D03*
X92304Y843420D03*
X138000Y319700D03*
X134000Y674700D03*
Y682200D03*
X143500Y706200D03*
X153500Y674200D03*
Y682200D03*
X163000Y706200D03*
X168300Y453500D03*
X172800D03*
X187300D03*
X191800D03*
X195000Y887200D03*
X207500Y710700D03*
X212000D03*
X208000Y887200D03*
X216500Y710700D03*
X221000D03*
X236500Y832700D03*
X250000Y710700D03*
X265500Y901200D03*
X277500Y899200D03*
X296000Y91200D03*
X300500D03*
X305000D03*
X329055Y556200D03*
X333000Y97700D03*
X341000Y108740D03*
X347000Y108629D03*
X341000Y116240D03*
X346500Y914200D03*
X338000Y956200D03*
X342500D03*
X347000D03*
X353000Y84700D03*
X355055Y552700D03*
X355500Y914200D03*
X351000D03*
X359500D03*
X351500Y956200D03*
X356000D03*
X360500D03*
X375055Y467450D03*
X391055Y302700D03*
X380555Y467450D03*
X391555D03*
X386055D03*
X389000Y873700D03*
X393500D03*
X392000Y955200D03*
X420429Y261100D03*
X427555Y295200D03*
X433500Y239700D03*
X429429Y261100D03*
X444778Y812200D03*
X438278D03*
X444278Y875700D03*
X455000Y113200D03*
X459500D03*
X450778Y875700D03*
X475778Y812200D03*
X469278D03*
X473778Y875700D03*
X480278D03*
X544000Y154700D03*
X559000D03*
X554000D03*
X553055Y330700D03*
X557055D03*
X564000Y154700D03*
X585000Y256200D03*
X638876Y96914D03*
X656876D03*
X652376D03*
X647876D03*
X643376D03*
X655964Y444238D03*
X654962Y484164D03*
X674666Y90244D03*
X661376Y96914D03*
X668462Y484164D03*
X663962D03*
X682968Y773684D03*
Y765684D03*
X706716Y90484D03*
X700216Y151984D03*
X720032Y57416D03*
X724532Y65416D03*
X711216Y90484D03*
X720216D03*
X709216Y151984D03*
X713716D03*
X718216D03*
X722716D03*
X714000Y874700D03*
X740500Y82700D03*
X740748Y152200D03*
X727216Y151984D03*
X732500Y482200D03*
X745500Y152200D03*
X767000Y467200D03*
X760500Y484700D03*
X775748Y184200D03*
X779998Y676754D03*
X789500Y884700D03*
X798774Y437278D03*
X792500Y661700D03*
X802000Y731700D03*
X798000D03*
X822500Y407700D03*
X810000Y731700D03*
X829055Y273700D03*
X830500Y410700D03*
X867500Y624700D03*
Y617200D03*
X865468Y709984D03*
X875000Y444200D03*
X879500D03*
X880500Y478700D03*
X873500Y679700D03*
X953450Y441400D03*
X952450Y466900D03*
X957950Y441400D03*
X957068Y466950D03*
X1031000Y148700D03*
X1028716Y862168D03*
X1065688Y753304D03*
X1065838Y761244D03*
X1080468Y210984D03*
X1079688Y753434D03*
X1101500Y457700D03*
X1097000D03*
X1101468Y850484D03*
X1111000Y637700D03*
X1105968Y850484D03*
X1129000Y637700D03*
X1133000D03*
X1125000D03*
X1151500Y622700D03*
X1142000Y625700D03*
X1137000Y634700D03*
X1143218Y757064D03*
X1162468Y253484D03*
X1167500Y624200D03*
X1155500Y637700D03*
X1159500D03*
X1167500D03*
X1163500D03*
X1178000Y363700D03*
X1182000D03*
X1183000Y403700D03*
X1199000D03*
X1187000D03*
X1186500Y600700D03*
X1197000Y855200D03*
X1217000Y634200D03*
X1207000Y764700D03*
X1212500D03*
X1211000Y855200D03*
X1222500Y435700D03*
X1222000Y443700D03*
X1251000Y476200D03*
Y468700D03*
X1250600Y838800D03*
X1277000Y709200D03*
X1281000Y719700D03*
X1284500Y326700D03*
X1289468Y662984D03*
X1292968Y846984D03*
X1297468D03*
X1303784Y778732D03*
X1308784D03*
X1313784D03*
X1312500Y834200D03*
X1308500D03*
X1304500D03*
X1317000Y332200D03*
X1322500D03*
X1318500Y448700D03*
X1323117Y622112D03*
X1316500Y834200D03*
X1320500D03*
X1317500Y906200D03*
X1342000Y81200D03*
X1337468Y676484D03*
X1333468D03*
X1355000Y423700D03*
X1360617Y623112D03*
G54D132*
X761966Y183784D03*
X769466Y179909D03*
Y187659D03*
X775534Y658532D03*
X783034Y654657D03*
Y662407D03*
X885750Y56500D03*
X893250Y52625D03*
Y60375D03*
X1256250Y559000D03*
X1263750Y562875D03*
Y555125D03*
X1256350Y844100D03*
X1263850Y840225D03*
Y847975D03*
G54D12*
X15000Y1008622D03*
X90119Y72219D03*
X227041Y1008622D03*
X653974Y1008621D03*
X955315Y850829D03*
X1157095Y128841D03*
X1385000Y1008622D03*
X1387875Y-15015D03*
G54D105*
X537994Y303150D03*
X825984D03*
G54D150*
X1066929Y43267D03*
X1057086D03*
X1084646D03*
X1074803D03*
G54D31*
X43804Y932420D03*
X100772Y767704D03*
X85304Y884420D03*
X101804Y932420D03*
X216500Y431200D03*
X266500Y211200D03*
X270500D03*
X310429Y264200D03*
X328500Y94200D03*
X315429Y264200D03*
X320429D03*
X321023Y548483D03*
X325023D03*
X337000Y94200D03*
X333500Y946300D03*
X361929Y271200D03*
X352929D03*
X370929D03*
X375000D03*
X378929D03*
X674122Y126632D03*
X675055Y262700D03*
X679055D03*
X706055D03*
X710055D03*
X731468Y779684D03*
X727468D03*
X729468Y811184D03*
X725968D03*
X746716Y122984D03*
X750216D03*
X756000Y579700D03*
X788500Y658200D03*
X787500Y774700D03*
X791500D03*
X826500Y404200D03*
X854820Y344580D03*
X858500Y432700D03*
X880820Y348080D03*
X994500Y536700D03*
X1008500D03*
X1024716Y858668D03*
X1023716Y907668D03*
X1065500Y64200D03*
X1099500Y256200D03*
Y753200D03*
X1096000Y816200D03*
X1099468Y884484D03*
X1103000Y753200D03*
X1134500Y826910D03*
X1121968Y846984D03*
X1137748Y753484D03*
X1135468Y878984D03*
X1179677Y227700D03*
X1183177D03*
X1199677Y230200D03*
X1195677D03*
X1196500Y757700D03*
X1188000Y753700D03*
X1273000Y705700D03*
X1300784Y830732D03*
X1324500Y306200D03*
X1327500Y433200D03*
X1346617Y619612D03*
X1350617Y621112D03*
X1364617Y619612D03*
G54D115*
X672600Y348500D03*
Y369000D03*
X697400Y348500D03*
Y369000D03*
G54D124*
X722700Y107784D03*
X720732D03*
X718763D03*
X716795D03*
X714826D03*
X712858D03*
Y134784D03*
X714826D03*
X716795D03*
X718763D03*
X720732D03*
X722700D03*
X730574Y107784D03*
X728606D03*
X726637D03*
X724669D03*
Y134784D03*
X726637D03*
X728606D03*
X730574D03*
G54D133*
X786500Y397557D03*
Y419443D03*
X1343500Y383557D03*
Y405443D03*
G54D142*
X851892Y391835D03*
X849333D03*
X846774D03*
X844215D03*
X841656D03*
Y411321D03*
X844215D03*
X846774D03*
X849333D03*
X851892D03*
X1116468Y860541D03*
X1113909D03*
X1111350D03*
Y880027D03*
X1113909D03*
X1116468D03*
X1121586Y860541D03*
X1119027D03*
Y880027D03*
X1121586D03*
G54D40*
X106654Y794785D03*
Y796750D03*
Y798720D03*
Y800690D03*
Y802655D03*
X122954Y794785D03*
Y802655D03*
Y800690D03*
Y798720D03*
Y796750D03*
X166700Y467345D03*
Y469315D03*
Y471285D03*
Y473255D03*
X175900Y467345D03*
Y473255D03*
Y471285D03*
Y469315D03*
X222673Y497608D03*
Y499578D03*
Y501543D03*
Y503513D03*
Y505483D03*
Y507453D03*
Y509418D03*
Y511388D03*
Y513358D03*
Y515323D03*
Y517293D03*
Y519263D03*
Y521228D03*
Y523198D03*
Y525168D03*
Y527138D03*
Y529103D03*
Y531073D03*
Y533043D03*
Y535008D03*
Y536978D03*
Y538948D03*
Y540913D03*
Y542883D03*
Y544853D03*
Y546823D03*
Y548788D03*
Y550758D03*
X298373Y499578D03*
Y497608D03*
Y515323D03*
Y513358D03*
Y511388D03*
Y509418D03*
Y507453D03*
Y505483D03*
Y503513D03*
Y501543D03*
Y533043D03*
Y531073D03*
Y529103D03*
Y527138D03*
Y525168D03*
Y523198D03*
Y521228D03*
Y519263D03*
Y517293D03*
Y548788D03*
Y546823D03*
Y544853D03*
Y542883D03*
Y540913D03*
Y538948D03*
Y536978D03*
Y535008D03*
Y550758D03*
X871420Y348835D03*
Y346865D03*
Y344895D03*
Y342925D03*
X862220D03*
Y344895D03*
Y346865D03*
Y348835D03*
X950850Y447745D03*
Y449715D03*
Y451685D03*
Y453655D03*
X960050Y449715D03*
Y447745D03*
Y453655D03*
Y451685D03*
X1110318Y263849D03*
Y265814D03*
Y267784D03*
Y269754D03*
Y271719D03*
X1126618Y269754D03*
Y267784D03*
Y265814D03*
Y263849D03*
Y271719D03*
X1288818Y641849D03*
Y643814D03*
Y645784D03*
Y647754D03*
Y649719D03*
X1288318Y673349D03*
Y675314D03*
Y677284D03*
Y679254D03*
Y681219D03*
X1305118Y647754D03*
Y645784D03*
Y643814D03*
Y641849D03*
Y649719D03*
X1304618Y679254D03*
Y677284D03*
Y675314D03*
Y673349D03*
Y681219D03*
G54D22*
X34304Y890520D03*
X29804D03*
X25304D03*
X38804D03*
Y898520D03*
X47804Y932520D03*
X58804Y714520D03*
X65804Y840020D03*
X76804Y714520D03*
X77804Y766520D03*
X73804D03*
X74304Y840020D03*
X83304D03*
X78804D03*
X99536Y759526D03*
X96772Y767804D03*
X92304Y840020D03*
X138000Y316300D03*
X134000Y678800D03*
Y671300D03*
X143500Y702800D03*
X153500Y678800D03*
Y670800D03*
X163000Y702800D03*
X168300Y450100D03*
X172800D03*
X187300D03*
X191800D03*
X195000Y883800D03*
X207500Y707300D03*
X212000D03*
X208000Y883800D03*
X216500Y707300D03*
X221000D03*
X236500Y829300D03*
X250000Y707300D03*
X265500Y897800D03*
X277500Y895800D03*
X296000Y87800D03*
X300500D03*
X305000D03*
X329055Y552800D03*
X341000Y105340D03*
X347000Y105229D03*
X333000Y94300D03*
X341000Y112840D03*
X346500Y910800D03*
X338000Y952800D03*
X342500D03*
X347000D03*
X353000Y81300D03*
X355055Y549300D03*
X355500Y910800D03*
X351000D03*
X359500D03*
X351500Y952800D03*
X356000D03*
X360500D03*
X375055Y464050D03*
X391055Y299300D03*
X380555Y464050D03*
X391555D03*
X386055D03*
X389000Y870300D03*
X393500D03*
X392000Y951800D03*
X420429Y257700D03*
X427555Y291800D03*
X433500Y236300D03*
X429429Y257700D03*
X444778Y808800D03*
X438278D03*
X444278Y872300D03*
X455000Y109800D03*
X459500D03*
X450778Y872300D03*
X475778Y808800D03*
X469278D03*
X473778Y872300D03*
X480278D03*
X544000Y151300D03*
X559000D03*
X554000D03*
X553055Y327300D03*
X557055D03*
X564000Y151300D03*
X585000Y252800D03*
X638876Y93514D03*
X656876D03*
X652376D03*
X647876D03*
X643376D03*
X655964Y440838D03*
X654962Y480764D03*
X674666Y86844D03*
X661376Y93514D03*
X668462Y480764D03*
X663962D03*
X682968Y762284D03*
Y770284D03*
X706716Y87084D03*
X700216Y148584D03*
X720032Y54016D03*
X724532Y62016D03*
X711216Y87084D03*
X720216D03*
X709216Y148584D03*
X713716D03*
X718216D03*
X722716D03*
X714000Y871300D03*
X740500Y79300D03*
X740748Y148800D03*
X727216Y148584D03*
X732500Y478800D03*
X745500Y148800D03*
X767000Y463800D03*
X760500Y481300D03*
X775748Y180800D03*
X779998Y673354D03*
X789500Y881300D03*
X798774Y433878D03*
X792500Y658300D03*
X802000Y728300D03*
X798000D03*
X822500Y404300D03*
X810000Y728300D03*
X829055Y270300D03*
X830500Y407300D03*
X867500Y613800D03*
Y621300D03*
X865468Y706584D03*
X875000Y440800D03*
X879500D03*
X880500Y475300D03*
X873500Y676300D03*
X953450Y438000D03*
X952450Y463500D03*
X957950Y438000D03*
X957068Y463550D03*
X1031000Y145300D03*
X1028716Y858768D03*
X1065688Y749904D03*
X1065838Y757844D03*
X1080468Y207584D03*
X1079688Y750034D03*
X1101500Y454300D03*
X1097000D03*
X1101468Y847084D03*
X1111000Y634300D03*
X1105968Y847084D03*
X1129000Y634300D03*
X1133000D03*
X1125000D03*
X1151500Y619300D03*
X1137000Y631300D03*
X1142000Y622300D03*
X1143218Y753664D03*
X1162468Y250084D03*
X1167500Y620800D03*
X1155500Y634300D03*
X1159500D03*
X1167500D03*
X1163500D03*
X1178000Y360300D03*
X1182000D03*
X1183000Y400300D03*
X1199000D03*
X1187000D03*
X1186500Y597300D03*
X1197000Y851800D03*
X1217000Y630800D03*
X1207000Y761300D03*
X1212500D03*
X1211000Y851800D03*
X1222500Y432300D03*
X1222000Y440300D03*
X1251000Y465300D03*
Y472800D03*
X1250600Y835400D03*
X1277000Y705800D03*
X1281000Y716300D03*
X1284500Y323300D03*
X1289468Y659584D03*
X1292968Y843584D03*
X1297468D03*
X1303784Y775332D03*
X1308784D03*
X1313784D03*
X1312500Y830800D03*
X1308500D03*
X1304500D03*
X1317000Y328800D03*
X1322500D03*
X1318500Y445300D03*
X1323117Y618712D03*
X1316500Y830800D03*
X1320500D03*
X1317500Y902800D03*
X1342000Y77800D03*
X1337468Y673084D03*
X1333468D03*
X1355000Y420300D03*
X1360617Y619712D03*
G54D160*
X1224016Y180709D03*
G54D151*
X1062000Y108750D03*
Y132250D03*
G54D13*
X35435Y373228D03*
X82675D03*
X180118Y729409D03*
Y739409D03*
X200118Y729409D03*
X190118D03*
X200118Y739409D03*
X190118D03*
X210118Y729409D03*
Y739409D03*
X230118Y729409D03*
X220118D03*
X230118Y739409D03*
X220118D03*
X250118Y729409D03*
X240118D03*
X250118Y739409D03*
X240118D03*
X260118Y729409D03*
Y739409D03*
X270118Y729409D03*
Y739409D03*
G54D106*
X545079Y290355D03*
Y315945D03*
X560829Y290355D03*
X556889Y298230D03*
X552954Y290355D03*
X549014Y298230D03*
X560829Y315945D03*
X556889Y308070D03*
X552954Y315945D03*
X549014Y308070D03*
X576574Y290355D03*
X572639Y298230D03*
X568699Y290355D03*
X564764Y298230D03*
X576574Y315945D03*
X572639Y308070D03*
X568699Y315945D03*
X564764Y308070D03*
X592324Y290355D03*
X588384Y298230D03*
X584449Y290355D03*
X580514Y298230D03*
X592324Y315945D03*
X588384Y308070D03*
X584449Y315945D03*
X580514Y308070D03*
X608069Y290355D03*
X604134Y298230D03*
X600199Y290355D03*
X596259Y298230D03*
X608069Y315945D03*
X604134Y308070D03*
X600199Y315945D03*
X596259Y308070D03*
X627754Y298230D03*
X623819Y290355D03*
X619884Y298230D03*
X615944Y290355D03*
X612009Y298230D03*
X627754Y308070D03*
X623819Y315945D03*
X619884Y308070D03*
X615944Y315945D03*
X612009Y308070D03*
X643504Y298230D03*
X639569Y290355D03*
X635629Y298230D03*
X631694Y290355D03*
X643504Y308070D03*
X639569Y315945D03*
X635629Y308070D03*
X631694Y315945D03*
X659254Y298230D03*
X655314Y290355D03*
X651379Y298230D03*
X647439Y290355D03*
X659254Y308070D03*
X655314Y315945D03*
X651379Y308070D03*
X647439Y315945D03*
X674999Y298230D03*
X671064Y290355D03*
X667124Y298230D03*
X663189Y290355D03*
X674999Y308070D03*
X671064Y315945D03*
X667124Y308070D03*
X663189Y315945D03*
X690749Y298230D03*
X686809Y290355D03*
X682874Y298230D03*
X678939Y290355D03*
X690749Y308070D03*
X686809Y315945D03*
X682874Y308070D03*
X678939Y315945D03*
X706494Y298230D03*
X702559Y290355D03*
X698624Y298230D03*
X694684Y290355D03*
X706494Y308070D03*
X702559Y315945D03*
X698624Y308070D03*
X694684Y315945D03*
X726179Y290355D03*
X722244Y298230D03*
X718309Y290355D03*
X714369Y298230D03*
X710434Y290355D03*
X726179Y315945D03*
X722244Y308070D03*
X718309Y315945D03*
X714369Y308070D03*
X710434Y315945D03*
X741929Y290355D03*
X737994Y298230D03*
X734054Y290355D03*
X730119Y298230D03*
X741929Y315945D03*
X737994Y308070D03*
X734054Y315945D03*
X730119Y308070D03*
X757679Y290355D03*
X753739Y298230D03*
X749804Y290355D03*
X745864Y298230D03*
X757679Y315945D03*
X753739Y308070D03*
X749804Y315945D03*
X745864Y308070D03*
X773424Y290355D03*
X769489Y298230D03*
X765549Y290355D03*
X761614Y298230D03*
X773424Y315945D03*
X769489Y308070D03*
X765549Y315945D03*
X761614Y308070D03*
X789174Y290355D03*
X785234Y298230D03*
X781299Y290355D03*
X777364Y298230D03*
X789174Y315945D03*
X785234Y308070D03*
X781299Y315945D03*
X777364Y308070D03*
X804919Y290355D03*
X800984Y298230D03*
X797049Y290355D03*
X793109Y298230D03*
X804919Y315945D03*
X800984Y308070D03*
X797049Y315945D03*
X793109Y308070D03*
X820669Y290355D03*
X816734Y298230D03*
X812794Y290355D03*
X808859Y298230D03*
X820669Y315945D03*
X816734Y308070D03*
X812794Y315945D03*
X808859Y308070D03*
X840354Y298230D03*
X836419Y290355D03*
X832479Y298230D03*
X840354Y308070D03*
X836419Y315945D03*
X832479Y308070D03*
X856104Y298230D03*
X852164Y290355D03*
X848229Y298230D03*
X844289Y290355D03*
X856104Y308070D03*
X852164Y315945D03*
X848229Y308070D03*
X844289Y315945D03*
X871849Y298230D03*
X867914Y290355D03*
X863974Y298230D03*
X860039Y290355D03*
X871849Y308070D03*
X867914Y315945D03*
X863974Y308070D03*
X860039Y315945D03*
G54D32*
X43804Y936020D03*
X100772Y771304D03*
X85304Y888020D03*
X101804Y936020D03*
X216500Y434800D03*
X266500Y214800D03*
X270500D03*
X310429Y267800D03*
X328500Y97800D03*
X315429Y267800D03*
X320429D03*
X321023Y552083D03*
X325023D03*
X337000Y97800D03*
X333500Y949900D03*
X361929Y274800D03*
X352929D03*
X370929D03*
X375000D03*
X378929D03*
X674122Y130232D03*
X675055Y266300D03*
X679055D03*
X706055D03*
X710055D03*
X731468Y783284D03*
X727468D03*
X729468Y814784D03*
X725968D03*
X746716Y126584D03*
X750216D03*
X756000Y583300D03*
X788500Y661800D03*
X787500Y778300D03*
X791500D03*
X826500Y407800D03*
X854820Y348180D03*
X858500Y436300D03*
X880820Y351680D03*
X994500Y540300D03*
X1008500D03*
X1024716Y862268D03*
X1023716Y911268D03*
X1065500Y67800D03*
X1099500Y259800D03*
Y756800D03*
X1096000Y819800D03*
X1099468Y888084D03*
X1103000Y756800D03*
X1134500Y830510D03*
X1121968Y850584D03*
X1137748Y757084D03*
X1135468Y882584D03*
X1179677Y231300D03*
X1183177D03*
X1199677Y233800D03*
X1195677D03*
X1196500Y761300D03*
X1188000Y757300D03*
X1273000Y709300D03*
X1300784Y834332D03*
X1324500Y309800D03*
X1327500Y436800D03*
X1346617Y623212D03*
X1350617Y624712D03*
X1364617Y623212D03*
G54D143*
X941260Y371535D03*
X949134D03*
X941260Y388465D03*
X949134D03*
X957008Y371535D03*
X964882D03*
X957008Y388465D03*
X964882D03*
X972756Y371535D03*
Y388465D03*
G54D170*
X1301500Y392957D03*
Y415043D03*
G54D125*
X710889Y107284D03*
Y135284D03*
X732543Y107284D03*
Y135284D03*
X789727Y444972D03*
X783821D03*
Y457184D03*
X789727D03*
X1344953Y430394D03*
X1339047D03*
Y442606D03*
X1344953D03*
G54D23*
X48820Y403503D03*
X45670D03*
X42520D03*
X39370D03*
X50395Y393623D03*
X47245D03*
X44095D03*
X40945D03*
X67715Y403503D03*
X64565D03*
X61415D03*
X58270D03*
X55120D03*
X66140Y393623D03*
X62990D03*
X59840D03*
X56695D03*
X53545D03*
X51970Y403503D03*
X77165D03*
X74015D03*
X70865D03*
X78740Y393623D03*
X75590D03*
X72440D03*
X69290D03*
X166141Y303465D03*
X162992D03*
X164567Y313347D03*
X161417D03*
X181889Y303465D03*
X178740D03*
X175590D03*
X172441D03*
X169291D03*
X180315Y313347D03*
X177165D03*
X174015D03*
X170866D03*
X167716D03*
X197637Y303465D03*
X194488D03*
X191338D03*
X188189D03*
X185039D03*
X196063Y313347D03*
X192913D03*
X189763D03*
X186614D03*
X183464D03*
X213385Y303465D03*
X210236D03*
X207086D03*
X203937D03*
X200787D03*
X214960Y313347D03*
X211811D03*
X208661D03*
X205511D03*
X202362D03*
X199212D03*
X216535Y303465D03*
G54D134*
X786774Y451078D03*
X1342000Y436500D03*
G54D116*
X678500Y388671D03*
Y420329D03*
G54D107*
X590315Y9134D03*
Y19134D03*
X649527Y9134D03*
Y19134D03*
Y29134D03*
G54D50*
X153937Y238898D03*
Y246772D03*
Y260551D03*
X224015Y234961D03*
Y246772D03*
Y260551D03*
G54D14*
X34500Y692000D03*
X56000Y7500D03*
X56804Y768220D03*
X57500Y993500D03*
X125000Y827500D03*
X314429Y294500D03*
X366555Y455500D03*
X462500Y86000D03*
X526055Y295500D03*
X1086000Y592000D03*
X1184000Y793500D03*
X1341800Y788600D03*
X1367500Y995000D03*
G54D161*
X1224016Y386221D03*
G54D41*
X114174Y1007910D03*
X271653D03*
X723623D03*
G54D152*
X1077000Y238000D03*
Y260000D03*
G54D51*
X155600Y465300D03*
X177543Y537396D03*
X193800Y848000D03*
X200800Y431500D03*
X320793Y450373D03*
X321823Y483783D03*
X336729Y241500D03*
X386300Y947000D03*
X472855Y301500D03*
Y305500D03*
X580300Y66000D03*
Y62000D03*
X631800Y575000D03*
X677386Y107874D03*
X690548Y122500D03*
X694762Y455464D03*
X713300Y568000D03*
X719800Y864000D03*
X785300Y355500D03*
X775574Y475078D03*
X800574D03*
X822800Y368500D03*
X821300Y849500D03*
X852800Y385000D03*
X849800Y638500D03*
X941250Y448700D03*
X1020300Y277500D03*
Y281500D03*
X1011300Y480500D03*
X1015516Y898468D03*
X1033300Y137000D03*
X1050800Y930000D03*
X1077229Y73758D03*
X1096268Y863284D03*
X1105300Y776500D03*
Y772500D03*
X1143300Y862000D03*
X1210300Y432500D03*
X1205800Y753000D03*
X1202268Y807784D03*
Y804284D03*
X1253800Y699500D03*
X1275800Y564500D03*
X1308300Y855000D03*
Y858500D03*
X1316417Y603912D03*
X1340300Y452000D03*
X1357800D03*
G54D117*
X672962Y456464D03*
X1048968Y155284D03*
X1269468Y444284D03*
G54D60*
X184200Y861000D03*
X187700Y852000D03*
X188200Y874000D03*
X209700Y816500D03*
X452629Y101500D03*
X596598Y426116D03*
Y431116D03*
Y441116D03*
Y436116D03*
Y451116D03*
Y446116D03*
X670948Y56500D03*
Y63500D03*
X719400Y202000D03*
X763974Y441078D03*
X846700Y720000D03*
X870168Y709784D03*
X1038700Y105500D03*
Y111000D03*
X1100700Y780500D03*
X1147100Y604700D03*
X1249200Y716000D03*
X1287700Y363000D03*
X1302700Y564500D03*
X1311817Y577412D03*
X1325200Y420000D03*
X1336817Y562412D03*
G54D126*
X721716Y121284D03*
G54D180*
X1369720Y117145D03*
Y110415D03*
X1390004Y117145D03*
Y110415D03*
G54D15*
X33554Y844660D03*
Y849780D03*
Y847220D03*
X40054Y844660D03*
Y849780D03*
X201805Y532560D03*
Y530000D03*
Y527440D03*
X208305D03*
Y532560D03*
X201805Y545060D03*
Y542500D03*
Y539940D03*
X208305D03*
Y545060D03*
Y552940D03*
Y555500D03*
Y558060D03*
X201805D03*
Y552940D03*
X721250Y875560D03*
Y870440D03*
X727750D03*
Y873000D03*
Y875560D03*
X782750Y856060D03*
Y853500D03*
Y850940D03*
X789250D03*
Y856060D03*
X839250Y846440D03*
Y849000D03*
Y851560D03*
X832750D03*
Y846440D03*
X832250Y868560D03*
Y866000D03*
Y863440D03*
X838750D03*
Y868560D03*
X865250Y659940D03*
Y662500D03*
X858750Y659940D03*
X865250Y665060D03*
X858750D03*
X932250Y56940D03*
X925750D03*
X932250Y59500D03*
Y62060D03*
X925750D03*
X1003750Y467000D03*
Y464440D03*
Y469560D03*
X1010250Y464440D03*
Y469560D03*
G54D24*
X48820Y422933D03*
X67717D03*
X58268D03*
G54D171*
X1312500Y14200D03*
Y19800D03*
X1321000Y14200D03*
Y19800D03*
G54D162*
X1233050Y778453D03*
Y772547D03*
X1248950Y778465D03*
Y772547D03*
G54D135*
X780718Y450094D03*
Y452062D03*
X792830Y450094D03*
Y452062D03*
X1348056Y437484D03*
Y435516D03*
X1335944D03*
Y437484D03*
G54D153*
X1081260Y418200D03*
X1085000Y426800D03*
X1088740Y418200D03*
G54D108*
X585315Y44134D03*
X654527D03*
G54D42*
X110234Y1009860D03*
X133859D03*
X129919D03*
X125984D03*
X122049D03*
X118109D03*
X145669D03*
X149604D03*
X165354D03*
X161419D03*
X157479D03*
X153544D03*
X181104D03*
X177164D03*
X173229D03*
X169289D03*
X185039D03*
X279528D03*
X275588D03*
X267718D03*
X295273D03*
X291338D03*
X287403D03*
X283463D03*
X311023D03*
X307088D03*
X303148D03*
X299213D03*
X330708D03*
X326773D03*
X322833D03*
X318898D03*
X314958D03*
X346458D03*
X342518D03*
X338583D03*
X334643D03*
X362203D03*
X358268D03*
X354333D03*
X350393D03*
X377953D03*
X374018D03*
X370078D03*
X366143D03*
X393703D03*
X389763D03*
X385828D03*
X381888D03*
X409448D03*
X405513D03*
X401573D03*
X397638D03*
X429133D03*
X425198D03*
X421258D03*
X417323D03*
X413388D03*
X444883D03*
X440943D03*
X437008D03*
X433073D03*
X460628D03*
X456693D03*
X452758D03*
X448818D03*
X476378D03*
X472443D03*
X468503D03*
X464568D03*
X492128D03*
X488188D03*
X484253D03*
X480313D03*
X507873D03*
X503938D03*
X499998D03*
X496063D03*
X527558D03*
X523623D03*
X519683D03*
X515748D03*
X511813D03*
X543308D03*
X539368D03*
X535433D03*
X531498D03*
X559053D03*
X555118D03*
X574803D03*
X570868D03*
X566928D03*
X562993D03*
X590553D03*
X586613D03*
X582678D03*
X578738D03*
X594488D03*
X719683D03*
X739368D03*
X735433D03*
X731498D03*
X727558D03*
X755118D03*
X743308D03*
X770868D03*
X766928D03*
X762993D03*
X759053D03*
X790553D03*
X786613D03*
X782678D03*
X778738D03*
X774803D03*
X794488D03*
G54D33*
X59787Y669714D03*
X61362D03*
X62937D03*
X64512D03*
X66087D03*
Y691914D03*
X64512D03*
X62937D03*
X61362D03*
X59787D03*
X67662Y669714D03*
X69232D03*
X70807D03*
X72382D03*
X73957D03*
X75532D03*
X77107D03*
Y691914D03*
X75532D03*
X73957D03*
X72382D03*
X70807D03*
X69232D03*
X67662D03*
X94587Y669714D03*
X96162D03*
X97737D03*
X99312D03*
Y691914D03*
X97737D03*
X96162D03*
X94587D03*
X100887Y669714D03*
X102462D03*
X104032D03*
X105607D03*
X107182D03*
X108757D03*
X110332D03*
X111907D03*
Y691914D03*
X110332D03*
X108757D03*
X107182D03*
X105607D03*
X104032D03*
X102462D03*
X100887D03*
X323395Y517900D03*
X324970D03*
X326545D03*
X328120D03*
X329695D03*
Y540100D03*
X328120D03*
X326545D03*
X324970D03*
X323395D03*
X331270Y517900D03*
X332840D03*
X334415D03*
X335990D03*
X337565D03*
X339140D03*
X340715D03*
Y540100D03*
X339140D03*
X337565D03*
X335990D03*
X334415D03*
X332840D03*
X331270D03*
X347738Y517994D03*
X349313D03*
X350888D03*
X352463D03*
X354038D03*
X355613D03*
X357183D03*
X358758D03*
X360333D03*
X361908D03*
Y540194D03*
X360333D03*
X358758D03*
X357183D03*
X355613D03*
X354038D03*
X352463D03*
X350888D03*
X349313D03*
X347738D03*
X363483Y517994D03*
X365058D03*
Y540194D03*
X363483D03*
G54D144*
X945197Y380000D03*
X968819D03*
G54D181*
G01X-185516Y-508119D02*
Y-490619D01*
G01X-176346D02*
Y-508119D01*
G01Y-499369D02*
X-185516D01*
G01X-163431Y-508119D02*
X-165178Y-507827D01*
X-166706Y-506661D01*
X-168016Y-504911D01*
X-168890Y-502869D01*
X-169326Y-500536D01*
Y-498202D01*
X-168890Y-495869D01*
X-168016Y-493827D01*
X-166706Y-492078D01*
X-165178Y-490911D01*
X-163431Y-490619D01*
X-161685Y-490911D01*
X-160156Y-492078D01*
X-158846Y-493827D01*
X-157972Y-495869D01*
X-157536Y-498202D01*
Y-500536D01*
X-157972Y-502869D01*
X-158846Y-504911D01*
X-160156Y-506661D01*
X-161685Y-507827D01*
X-163431Y-508119D01*
G01X-150953D02*
Y-490619D01*
X-140909Y-508119D01*
Y-490619D01*
G01X-124064Y-508119D02*
X-132798D01*
Y-490619D01*
X-124064D01*
G01X-127558Y-499077D02*
X-132798D01*
G01X-110931Y-508119D02*
Y-500244D01*
X-115298Y-490619D01*
G01X-106564D02*
X-110931Y-500244D01*
G01X-74185Y-498786D02*
X-73311Y-497911D01*
X-72656Y-496453D01*
X-72219Y-494410D01*
X-72656Y-492661D01*
X-73529Y-491494D01*
X-75058Y-490619D01*
X-80953D01*
Y-508119D01*
X-73748D01*
X-72219Y-506953D01*
X-71346Y-505202D01*
X-70909Y-503161D01*
X-71346Y-501119D01*
X-72656Y-499369D01*
X-74185Y-498786D01*
X-80953D01*
G01X-63890Y-508119D02*
X-58431Y-490619D01*
X-52972Y-508119D01*
G01X-54938Y-501994D02*
X-61925D01*
G01X-45734Y-508119D02*
Y-490619D01*
X-41368D01*
X-39621Y-491494D01*
X-38311Y-492661D01*
X-37219Y-494410D01*
X-36346Y-496453D01*
X-36128Y-499369D01*
X-36346Y-502286D01*
X-37219Y-504328D01*
X-38311Y-506078D01*
X-39621Y-507244D01*
X-41368Y-508119D01*
X-45734D01*
G01X-22121Y-499369D02*
X-17754D01*
Y-504619D01*
X-19064Y-506369D01*
X-20593Y-507536D01*
X-22776Y-508119D01*
X-24959Y-507536D01*
X-26488Y-506369D01*
X-27798Y-504619D01*
X-28671Y-502577D01*
X-29108Y-500244D01*
Y-498202D01*
X-28671Y-496453D01*
X-27798Y-494410D01*
X-26488Y-492661D01*
X-25178Y-491494D01*
X-23431Y-490619D01*
X-21903D01*
X-20156Y-491202D01*
X-18846Y-492369D01*
G01X-1564Y-508119D02*
X-10298D01*
Y-490619D01*
X-1564D01*
G01X-5058Y-499077D02*
X-10298D01*
G01X7202Y-508119D02*
Y-490619D01*
X12661D01*
X14407Y-491494D01*
X15499Y-492661D01*
X15936Y-494994D01*
X15499Y-497328D01*
X14189Y-498786D01*
X12661Y-499661D01*
X7202D01*
G01X12661D02*
X15936Y-508119D01*
G01X48315Y-498786D02*
X49189Y-497911D01*
X49844Y-496453D01*
X50281Y-494410D01*
X49844Y-492661D01*
X48971Y-491494D01*
X47442Y-490619D01*
X41547D01*
Y-508119D01*
X48752D01*
X50281Y-506953D01*
X51154Y-505202D01*
X51591Y-503161D01*
X51154Y-501119D01*
X49844Y-499369D01*
X48315Y-498786D01*
X41547D01*
G01X58610Y-508119D02*
X64069Y-490619D01*
X69528Y-508119D01*
G01X67562Y-501994D02*
X60575D01*
G01X76984Y-505786D02*
X78731Y-507244D01*
X80696Y-508119D01*
X82442D01*
X84189Y-507244D01*
X85499Y-505786D01*
X86154Y-503744D01*
X85717Y-501703D01*
X84626Y-499952D01*
X82661Y-498786D01*
X80041Y-498202D01*
X78512Y-497036D01*
X77857Y-494994D01*
X78294Y-492952D01*
X79386Y-491494D01*
X80914Y-490619D01*
X82442D01*
X83971Y-491202D01*
X85281Y-492661D01*
G01X103436Y-508119D02*
X94702D01*
Y-490619D01*
X103436D01*
G01X99942Y-499077D02*
X94702D01*
G01X118315Y-498786D02*
X119189Y-497911D01*
X119844Y-496453D01*
X120281Y-494410D01*
X119844Y-492661D01*
X118971Y-491494D01*
X117442Y-490619D01*
X111547D01*
Y-508119D01*
X118752D01*
X120281Y-506953D01*
X121154Y-505202D01*
X121591Y-503161D01*
X121154Y-501119D01*
X119844Y-499369D01*
X118315Y-498786D01*
X111547D01*
G01X134069Y-508119D02*
X132322Y-507827D01*
X130794Y-506661D01*
X129484Y-504911D01*
X128610Y-502869D01*
X128174Y-500536D01*
Y-498202D01*
X128610Y-495869D01*
X129484Y-493827D01*
X130794Y-492078D01*
X132322Y-490911D01*
X134069Y-490619D01*
X135815Y-490911D01*
X137344Y-492078D01*
X138654Y-493827D01*
X139528Y-495869D01*
X139964Y-498202D01*
Y-500536D01*
X139528Y-502869D01*
X138654Y-504911D01*
X137344Y-506661D01*
X135815Y-507827D01*
X134069Y-508119D01*
G01X146110D02*
X151569Y-490619D01*
X157028Y-508119D01*
G01X155062Y-501994D02*
X148075D01*
G01X164702Y-508119D02*
Y-490619D01*
X170161D01*
X171907Y-491494D01*
X172999Y-492661D01*
X173436Y-494994D01*
X172999Y-497328D01*
X171689Y-498786D01*
X170161Y-499661D01*
X164702D01*
G01X170161D02*
X173436Y-508119D01*
G01X181766D02*
Y-490619D01*
X186132D01*
X187879Y-491494D01*
X189189Y-492661D01*
X190281Y-494410D01*
X191154Y-496453D01*
X191372Y-499369D01*
X191154Y-502286D01*
X190281Y-504328D01*
X189189Y-506078D01*
X187879Y-507244D01*
X186132Y-508119D01*
X181766D01*
G01X-37858Y-463119D02*
Y-445619D01*
X-32181Y-460202D01*
X-26504Y-445619D01*
Y-463119D01*
G01X-14681D02*
X-15991Y-462827D01*
X-17301Y-461661D01*
X-18175Y-459619D01*
X-18611Y-457286D01*
X-18175Y-454952D01*
X-17301Y-452911D01*
X-15991Y-451744D01*
X-14681Y-451453D01*
X-13371Y-451744D01*
X-12061Y-452911D01*
X-11188Y-454952D01*
X-10969Y-457286D01*
X-11188Y-459619D01*
X-12061Y-461661D01*
X-13371Y-462827D01*
X-14681Y-463119D01*
G01X6749Y-445619D02*
Y-463119D01*
G01Y-460495D02*
X5876Y-461953D01*
X4565Y-462827D01*
X3037Y-463119D01*
X1291Y-462536D01*
X-19Y-461078D01*
X-893Y-459328D01*
X-1111Y-457286D01*
X-893Y-455244D01*
X-19Y-453494D01*
X1291Y-452036D01*
X3037Y-451453D01*
X4565Y-451744D01*
X5657Y-452328D01*
X6749Y-453494D01*
G01X17044Y-455244D02*
X24031D01*
X23376Y-453202D01*
X22284Y-452036D01*
X20756Y-451453D01*
X19227Y-451744D01*
X17917Y-452619D01*
X17044Y-454661D01*
X16607Y-456411D01*
Y-458161D01*
X17044Y-459911D01*
X18136Y-461661D01*
X19446Y-462827D01*
X20974Y-463119D01*
X22502Y-462536D01*
X24031Y-460786D01*
G01X37819Y-463119D02*
Y-445619D01*
G01X281019Y-508119D02*
Y-490619D01*
X278399Y-494119D01*
G01Y-508119D02*
X283639D01*
G01X293716Y-504619D02*
X295025Y-506661D01*
X296772Y-507827D01*
X298737Y-508119D01*
X300484Y-507827D01*
X302231Y-506369D01*
X303322Y-504619D01*
X303541Y-502869D01*
X303104Y-500828D01*
X301576Y-499369D01*
X300047Y-498786D01*
X298082D01*
G01X300047D02*
X301357Y-497911D01*
X302449Y-496453D01*
X302886Y-494703D01*
X302449Y-492952D01*
X301357Y-491494D01*
X299392Y-490619D01*
X297427Y-490911D01*
X295462Y-492078D01*
G01X312307Y-506078D02*
X313836Y-507536D01*
X315582Y-508119D01*
X317329Y-507536D01*
X318857Y-505786D01*
X319949Y-503161D01*
X320386Y-500536D01*
Y-497328D01*
X319949Y-494703D01*
X318857Y-492369D01*
X317547Y-491202D01*
X316019Y-490619D01*
X314272Y-491202D01*
X312962Y-492369D01*
X312089Y-494119D01*
X311652Y-496453D01*
X312089Y-498494D01*
X313181Y-500536D01*
X314491Y-501703D01*
X316019Y-501994D01*
X317765Y-501411D01*
X319076Y-499952D01*
X320386Y-497328D01*
G01X336139Y-508119D02*
Y-490619D01*
X328060Y-503161D01*
X338978D01*
G01X351019Y-508119D02*
X352547Y-507827D01*
X354294Y-506953D01*
X355386Y-505495D01*
X355822Y-503452D01*
X355386Y-501411D01*
X354076Y-499661D01*
X352111Y-498786D01*
X349927D01*
X348617Y-498202D01*
X347525Y-496744D01*
X347089Y-494703D01*
X347744Y-492661D01*
X349272Y-491202D01*
X351019Y-490619D01*
X352765Y-491202D01*
X354294Y-492661D01*
X354949Y-494703D01*
X354512Y-496744D01*
X353421Y-498202D01*
X352111Y-498786D01*
X349927D01*
X347962Y-499661D01*
X346652Y-501411D01*
X346216Y-503452D01*
X346652Y-505495D01*
X347744Y-506953D01*
X349491Y-507827D01*
X351019Y-508119D01*
G01X267902Y-463119D02*
Y-445619D01*
X273142D01*
X274889Y-446494D01*
X276199Y-448536D01*
X276636Y-450869D01*
X276199Y-453202D01*
X275107Y-454952D01*
X273142Y-455828D01*
X267902D01*
G01X294572Y-447078D02*
X293262Y-446202D01*
X291734Y-445619D01*
X289987D01*
X288022Y-446494D01*
X286494Y-447952D01*
X285402Y-449703D01*
X284529Y-452619D01*
X284310Y-455244D01*
X284747Y-457869D01*
X285402Y-459619D01*
X286712Y-461369D01*
X288241Y-462536D01*
X289769Y-463119D01*
X291297D01*
X292826Y-462536D01*
X294136Y-461661D01*
X295228Y-460495D01*
G01X309015Y-453786D02*
X309889Y-452911D01*
X310544Y-451453D01*
X310981Y-449410D01*
X310544Y-447661D01*
X309671Y-446494D01*
X308142Y-445619D01*
X302247D01*
Y-463119D01*
X309452D01*
X310981Y-461953D01*
X311854Y-460202D01*
X312291Y-458161D01*
X311854Y-456119D01*
X310544Y-454369D01*
X309015Y-453786D01*
X302247D01*
G01X318219Y-468952D02*
X331319D01*
G01X337247Y-463119D02*
Y-445619D01*
X347291Y-463119D01*
Y-445619D01*
G01X359769Y-463119D02*
X358022Y-462827D01*
X356494Y-461661D01*
X355184Y-459911D01*
X354310Y-457869D01*
X353874Y-455536D01*
Y-453202D01*
X354310Y-450869D01*
X355184Y-448827D01*
X356494Y-447078D01*
X358022Y-445911D01*
X359769Y-445619D01*
X361515Y-445911D01*
X363044Y-447078D01*
X364354Y-448827D01*
X365228Y-450869D01*
X365664Y-453202D01*
Y-455536D01*
X365228Y-457869D01*
X364354Y-459911D01*
X363044Y-461661D01*
X361515Y-462827D01*
X359769Y-463119D01*
G01X410610Y-445619D02*
X416069Y-463119D01*
X421528Y-445619D01*
G01X437936Y-463119D02*
X429202D01*
Y-445619D01*
X437936D01*
G01X434442Y-454077D02*
X429202D01*
G01X446702Y-463119D02*
Y-445619D01*
X452161D01*
X453907Y-446494D01*
X454999Y-447661D01*
X455436Y-449994D01*
X454999Y-452328D01*
X453689Y-453786D01*
X452161Y-454661D01*
X446702D01*
G01X452161D02*
X455436Y-463119D01*
G01X468569Y-463702D02*
X468132Y-463411D01*
Y-462827D01*
X468569Y-462536D01*
X469006Y-462827D01*
Y-463411D01*
X468569Y-463702D01*
G01X433569Y-508119D02*
Y-490619D01*
X430949Y-494119D01*
G01Y-508119D02*
X436189D01*
G01X452815Y-498786D02*
X453689Y-497911D01*
X454344Y-496453D01*
X454781Y-494410D01*
X454344Y-492661D01*
X453471Y-491494D01*
X451942Y-490619D01*
X446047D01*
Y-508119D01*
X453252D01*
X454781Y-506953D01*
X455654Y-505202D01*
X456091Y-503161D01*
X455654Y-501119D01*
X454344Y-499369D01*
X452815Y-498786D01*
X446047D01*
G01X548519Y-490619D02*
Y-508119D01*
G01X543497Y-490619D02*
X553541D01*
G01X560342Y-508119D02*
Y-490619D01*
X566019Y-505202D01*
X571696Y-490619D01*
Y-508119D01*
G01X578060D02*
X583519Y-490619D01*
X588978Y-508119D01*
G01X587012Y-501994D02*
X580025D01*
G01X596434Y-505786D02*
X598181Y-507244D01*
X600146Y-508119D01*
X601892D01*
X603639Y-507244D01*
X604949Y-505786D01*
X605604Y-503744D01*
X605167Y-501703D01*
X604076Y-499952D01*
X602111Y-498786D01*
X599491Y-498202D01*
X597962Y-497036D01*
X597307Y-494994D01*
X597744Y-492952D01*
X598836Y-491494D01*
X600364Y-490619D01*
X601892D01*
X603421Y-491202D01*
X604731Y-492661D01*
G01X613716Y-508119D02*
Y-490619D01*
G01X622012D02*
X613716Y-501411D01*
G01X623322Y-508119D02*
X617427Y-496453D01*
G01X544152Y-445619D02*
Y-463119D01*
X552886D01*
G01X569949D02*
Y-451453D01*
G01Y-453494D02*
X569076Y-452328D01*
X567765Y-451744D01*
X566237Y-451453D01*
X564709Y-452036D01*
X563399Y-453202D01*
X562525Y-454952D01*
X562089Y-457286D01*
X562525Y-459619D01*
X563399Y-461369D01*
X564709Y-462536D01*
X566237Y-463119D01*
X567765Y-462827D01*
X569076Y-461953D01*
X569949Y-460786D01*
G01X578934Y-468369D02*
X580244Y-468952D01*
X581991Y-468369D01*
X583082Y-467203D01*
X583956Y-465744D01*
X585265Y-461078D01*
X588104Y-451453D01*
G01X581117D02*
X585265Y-461078D01*
G01X597744Y-455244D02*
X604731D01*
X604076Y-453202D01*
X602984Y-452036D01*
X601456Y-451453D01*
X599927Y-451744D01*
X598617Y-452619D01*
X597744Y-454661D01*
X597307Y-456411D01*
Y-458161D01*
X597744Y-459911D01*
X598836Y-461661D01*
X600146Y-462827D01*
X601674Y-463119D01*
X603202Y-462536D01*
X604731Y-460786D01*
G01X615462Y-463119D02*
Y-451453D01*
G01Y-453786D02*
X616554Y-452619D01*
X617646Y-451744D01*
X619174Y-451453D01*
X620265Y-451744D01*
X621576Y-452619D01*
G01X686702Y-490619D02*
Y-508119D01*
X695436D01*
G01X703984Y-513369D02*
X705294Y-513952D01*
X707041Y-513369D01*
X708132Y-512203D01*
X709006Y-510744D01*
X710315Y-506078D01*
X713154Y-496453D01*
G01X706167D02*
X710315Y-506078D01*
G01X722357Y-508119D02*
Y-496453D01*
G01Y-499369D02*
X723231Y-497911D01*
X724541Y-496744D01*
X726287Y-496453D01*
X727815Y-496744D01*
X729126Y-497911D01*
X729781Y-499952D01*
Y-508119D01*
G01X739857D02*
Y-496453D01*
G01Y-499369D02*
X740731Y-497911D01*
X742041Y-496744D01*
X743787Y-496453D01*
X745315Y-496744D01*
X746626Y-497911D01*
X747281Y-499952D01*
Y-508119D01*
G01X774202Y-490619D02*
Y-508119D01*
X782936D01*
G01X796069Y-496453D02*
Y-508119D01*
G01Y-491786D02*
X795632Y-491494D01*
Y-490911D01*
X796069Y-490619D01*
X796506Y-490911D01*
Y-491494D01*
X796069Y-491786D01*
G01X809857Y-496453D02*
Y-504619D01*
X810731Y-506661D01*
X812041Y-507827D01*
X813569Y-508119D01*
X815097Y-507827D01*
X816407Y-506661D01*
X817281Y-504619D01*
G01Y-508119D02*
Y-496453D01*
G01X686266Y-463119D02*
Y-445619D01*
X690632D01*
X692379Y-446494D01*
X693689Y-447661D01*
X694781Y-449410D01*
X695654Y-451453D01*
X695872Y-454369D01*
X695654Y-457286D01*
X694781Y-459328D01*
X693689Y-461078D01*
X692379Y-462244D01*
X690632Y-463119D01*
X686266D01*
G01X705294Y-455244D02*
X712281D01*
X711626Y-453202D01*
X710534Y-452036D01*
X709006Y-451453D01*
X707477Y-451744D01*
X706167Y-452619D01*
X705294Y-454661D01*
X704857Y-456411D01*
Y-458161D01*
X705294Y-459911D01*
X706386Y-461661D01*
X707696Y-462827D01*
X709224Y-463119D01*
X710752Y-462536D01*
X712281Y-460786D01*
G01X722794Y-461078D02*
X723886Y-462244D01*
X725414Y-463119D01*
X726724D01*
X728034Y-462536D01*
X728907Y-461661D01*
X729344Y-460495D01*
X729126Y-458744D01*
X728252Y-457869D01*
X724322Y-456119D01*
X723449Y-454077D01*
X723886Y-452619D01*
X724759Y-451744D01*
X726069Y-451453D01*
X727379Y-451744D01*
X728689Y-452619D01*
G01X743569Y-451453D02*
Y-463119D01*
G01Y-446786D02*
X743132Y-446494D01*
Y-445911D01*
X743569Y-445619D01*
X744006Y-445911D01*
Y-446494D01*
X743569Y-446786D01*
G01X758012Y-467494D02*
X759541Y-468661D01*
X761287Y-468952D01*
X762815Y-468661D01*
X764126Y-467203D01*
X764999Y-465161D01*
Y-451453D01*
G01Y-453786D02*
X764126Y-452619D01*
X762815Y-451744D01*
X761287Y-451453D01*
X759541Y-452036D01*
X758449Y-453202D01*
X757575Y-455244D01*
X757139Y-457286D01*
X757357Y-459036D01*
X758231Y-461078D01*
X759541Y-462536D01*
X761287Y-463119D01*
X762597Y-462827D01*
X764126Y-461661D01*
X764999Y-460495D01*
G01X774857Y-463119D02*
Y-451453D01*
G01Y-454369D02*
X775731Y-452911D01*
X777041Y-451744D01*
X778787Y-451453D01*
X780315Y-451744D01*
X781626Y-452911D01*
X782281Y-454952D01*
Y-463119D01*
G01X792794Y-455244D02*
X799781D01*
X799126Y-453202D01*
X798034Y-452036D01*
X796506Y-451453D01*
X794977Y-451744D01*
X793667Y-452619D01*
X792794Y-454661D01*
X792357Y-456411D01*
Y-458161D01*
X792794Y-459911D01*
X793886Y-461661D01*
X795196Y-462827D01*
X796724Y-463119D01*
X798252Y-462536D01*
X799781Y-460786D01*
G01X810512Y-463119D02*
Y-451453D01*
G01Y-453786D02*
X811604Y-452619D01*
X812696Y-451744D01*
X814224Y-451453D01*
X815315Y-451744D01*
X816626Y-452619D01*
G01X857269Y-508119D02*
Y-490619D01*
X854649Y-494119D01*
G01Y-508119D02*
X859889D01*
G01X874769D02*
Y-490619D01*
X872149Y-494119D01*
G01Y-508119D02*
X877389D01*
G01X888339Y-508702D02*
X896199Y-490619D01*
G01X909769Y-508119D02*
Y-490619D01*
X907149Y-494119D01*
G01Y-508119D02*
X912389D01*
G01X922466Y-504619D02*
X923775Y-506661D01*
X925522Y-507827D01*
X927487Y-508119D01*
X929234Y-507827D01*
X930981Y-506369D01*
X932072Y-504619D01*
X932291Y-502869D01*
X931854Y-500828D01*
X930326Y-499369D01*
X928797Y-498786D01*
X926832D01*
G01X928797D02*
X930107Y-497911D01*
X931199Y-496453D01*
X931636Y-494703D01*
X931199Y-492952D01*
X930107Y-491494D01*
X928142Y-490619D01*
X926177Y-490911D01*
X924212Y-492078D01*
G01X940839Y-508702D02*
X948699Y-490619D01*
G01X958121Y-493536D02*
X959431Y-491786D01*
X960959Y-490911D01*
X962706Y-490619D01*
X964889Y-491202D01*
X966417Y-492661D01*
X966854Y-494410D01*
X966636Y-496161D01*
X965762Y-497619D01*
X961396Y-500536D01*
X959431Y-502577D01*
X958121Y-505495D01*
X957684Y-508119D01*
X966854D01*
G01X979769Y-490619D02*
X978022Y-491202D01*
X976712Y-492661D01*
X975839Y-494410D01*
X975184Y-496744D01*
X974966Y-499369D01*
X975184Y-501994D01*
X975839Y-504328D01*
X976712Y-506078D01*
X978022Y-507536D01*
X979769Y-508119D01*
X981515Y-507536D01*
X982826Y-506078D01*
X983699Y-504328D01*
X984354Y-501994D01*
X984572Y-499369D01*
X984354Y-496744D01*
X983699Y-494410D01*
X982826Y-492661D01*
X981515Y-491202D01*
X979769Y-490619D01*
G01X997269Y-508119D02*
Y-490619D01*
X994649Y-494119D01*
G01Y-508119D02*
X999889D01*
G01X1017389D02*
Y-490619D01*
X1009310Y-503161D01*
X1020228D01*
G01X904966Y-463119D02*
Y-445619D01*
X909332D01*
X911079Y-446494D01*
X912389Y-447661D01*
X913481Y-449410D01*
X914354Y-451453D01*
X914572Y-454369D01*
X914354Y-457286D01*
X913481Y-459328D01*
X912389Y-461078D01*
X911079Y-462244D01*
X909332Y-463119D01*
X904966D01*
G01X931199D02*
Y-451453D01*
G01Y-453494D02*
X930326Y-452328D01*
X929015Y-451744D01*
X927487Y-451453D01*
X925959Y-452036D01*
X924649Y-453202D01*
X923775Y-454952D01*
X923339Y-457286D01*
X923775Y-459619D01*
X924649Y-461369D01*
X925959Y-462536D01*
X927487Y-463119D01*
X929015Y-462827D01*
X930326Y-461953D01*
X931199Y-460786D01*
G01X944769Y-445619D02*
Y-463119D01*
G01X941712Y-451453D02*
X947826D01*
G01X958994Y-455244D02*
X965981D01*
X965326Y-453202D01*
X964234Y-452036D01*
X962706Y-451453D01*
X961177Y-451744D01*
X959867Y-452619D01*
X958994Y-454661D01*
X958557Y-456411D01*
Y-458161D01*
X958994Y-459911D01*
X960086Y-461661D01*
X961396Y-462827D01*
X962924Y-463119D01*
X964452Y-462536D01*
X965981Y-460786D01*
G54D34*
X63304Y714520D03*
X55304Y750520D03*
X63272Y794304D03*
X58772D03*
X67772D03*
X81304Y714520D03*
X69804Y840020D03*
X96772Y714304D03*
X92772D03*
X87804Y840020D03*
X103804Y759520D03*
X102304Y887020D03*
X127654Y308753D03*
X179500Y862300D03*
X189555Y566800D03*
X194500Y861300D03*
X199000Y883800D03*
X210000Y829300D03*
X212000Y883800D03*
X232000Y829300D03*
X228000D03*
X220000D03*
X224000D03*
X216000Y883800D03*
X225000Y887300D03*
X229500D03*
X234623Y565983D03*
X273500Y197800D03*
X313485Y245172D03*
X312555Y439300D03*
X317985Y245172D03*
X341000Y94300D03*
X347000Y112729D03*
X357429Y246800D03*
X361929D03*
X352929D03*
X361178Y982300D03*
X366429Y246800D03*
X375429D03*
X370929D03*
X379929D03*
X376000Y869800D03*
X371500D03*
X380000Y918800D03*
X375500D03*
X373678Y982300D03*
X386555Y299300D03*
X395555D03*
X384500Y870300D03*
X384000Y918800D03*
X396929Y253800D03*
X412500Y265300D03*
X400555Y299300D03*
X405555D03*
X409555D03*
X398000Y870300D03*
X424929Y249700D03*
X420429D03*
X424929Y257700D03*
X423055Y293800D03*
X418555Y299300D03*
X414055D03*
X434540Y106300D03*
X440000Y236300D03*
X433929Y257700D03*
X444778Y805300D03*
X438278D03*
X444278Y875800D03*
X458555Y293300D03*
X450778Y875800D03*
X475778Y805300D03*
X469278D03*
X473778Y875800D03*
X480278D03*
X549000Y151300D03*
X549055Y327300D03*
X558955Y368200D03*
X554955D03*
X571000Y151300D03*
X659462Y480764D03*
X682382Y122742D03*
X678222Y122892D03*
X686432Y126312D03*
X690512Y126252D03*
X704716Y148584D03*
X698968Y779284D03*
X704000Y884800D03*
X724532Y54016D03*
X720032Y62016D03*
X715716Y87084D03*
X715468Y754784D03*
X736248Y148800D03*
X731716Y148584D03*
X725748Y180800D03*
X726000Y891300D03*
X763000Y455800D03*
X767000D03*
Y471800D03*
X765998Y707854D03*
X770498D03*
X788774Y475378D03*
X779774D03*
X780500Y881300D03*
X785000D03*
X806000Y728300D03*
X838055Y270300D03*
X833555D03*
X847055D03*
X851555D03*
X856055D03*
X842555D03*
X866500Y100800D03*
X865055Y270300D03*
X860555D03*
X868820Y356680D03*
X863820D03*
X867000Y432800D03*
X862500D03*
X869468Y701584D03*
X879500Y87800D03*
X873468Y701584D03*
X919000Y51800D03*
X998000Y480800D03*
X1003000D03*
X999000Y536800D03*
X1003000D03*
X1010500Y451800D03*
X1011000Y496800D03*
X1017000Y536800D03*
X1013000D03*
X1029500Y120800D03*
X1025500Y133300D03*
X1035000Y175300D03*
X1027716Y907768D03*
X1032216D03*
X1039500Y175300D03*
X1070478Y750024D03*
X1074968Y749984D03*
X1070098Y757884D03*
X1093961Y99842D03*
X1089961D03*
X1089500Y408800D03*
X1088000Y454300D03*
X1092500D03*
X1087988Y741924D03*
X1101968Y806584D03*
X1117500Y614300D03*
X1103000Y634300D03*
X1107000D03*
X1115000D03*
X1111000Y742300D03*
X1107468Y806384D03*
X1106500Y833800D03*
X1122000Y614300D03*
X1149934Y581472D03*
X1137500Y622300D03*
X1151500Y626800D03*
X1146500Y622300D03*
X1146000Y634300D03*
X1151500D03*
X1135468Y858584D03*
X1159500Y620300D03*
X1179000Y400300D03*
X1172000Y753800D03*
X1180000D03*
X1184000D03*
X1176000D03*
X1191000Y400300D03*
X1195000D03*
X1189000Y742300D03*
X1192000Y753800D03*
X1213000Y630800D03*
X1209000D03*
X1205000D03*
X1201000D03*
X1201968Y761084D03*
X1215716Y805768D03*
X1211216D03*
X1207000Y805800D03*
X1215500Y851800D03*
X1201500D03*
X1226500Y440300D03*
X1225500Y789800D03*
X1220000Y805800D03*
X1246500Y465300D03*
X1242000D03*
X1238100Y853900D03*
X1257000Y36300D03*
X1271500Y545300D03*
X1276000Y660300D03*
X1281000Y705800D03*
X1277000Y716300D03*
X1295500Y30800D03*
X1284500Y314800D03*
X1293968Y659584D03*
X1285000Y659800D03*
X1310500Y39800D03*
X1314500D03*
X1299968Y658084D03*
X1303784Y785832D03*
X1308784D03*
X1314284D03*
X1312500Y854050D03*
X1307468Y913584D03*
X1301968D03*
X1312468D03*
X1327000Y328800D03*
X1323500Y433300D03*
Y445300D03*
X1332117Y618712D03*
X1327617D03*
X1328968Y673084D03*
X1326000Y854050D03*
X1317000D03*
X1321500D03*
X1316968Y913584D03*
X1332500Y50800D03*
X1336500Y135300D03*
X1338500Y456300D03*
X1347468Y453084D03*
X1352000Y78300D03*
X1363117Y562212D03*
X1354417Y619712D03*
G54D16*
X26504Y840720D03*
X26500Y854200D03*
X51504Y842720D03*
X66004Y830720D03*
X78004Y889720D03*
X92472Y770504D03*
X92504Y790220D03*
Y798220D03*
Y806720D03*
Y811220D03*
X138700Y666500D03*
X141004Y808220D03*
Y803720D03*
Y799720D03*
Y812720D03*
X155500Y469800D03*
X165255Y530000D03*
X157255D03*
X163255Y550500D03*
X161200Y666500D03*
X152700Y844000D03*
X168500Y457800D03*
X190500Y474800D03*
X185255Y525500D03*
X185443Y537396D03*
X194200Y869500D03*
X211223Y521183D03*
X215700Y812000D03*
X221755Y560000D03*
Y564500D03*
X240700Y423000D03*
Y427000D03*
X247200Y855500D03*
Y859500D03*
Y847500D03*
X294859Y419678D03*
X324200Y98000D03*
X319205Y313152D03*
X319129Y334500D03*
X318129Y348500D03*
Y354000D03*
X344629Y237500D03*
X359723Y463783D03*
X358723Y473783D03*
Y478283D03*
X359635Y468450D03*
X358723Y482783D03*
X379255Y330500D03*
Y335000D03*
Y339500D03*
Y344000D03*
Y357500D03*
Y362000D03*
X365005Y405270D03*
Y410000D03*
Y414500D03*
Y419000D03*
X402200Y265400D03*
X405700Y885000D03*
X410700Y915500D03*
Y911500D03*
X429200Y236500D03*
X426455Y283200D03*
Y279200D03*
X430700Y941500D03*
Y945500D03*
X458200Y117500D03*
X465700Y185000D03*
X600200Y200500D03*
Y205000D03*
Y214000D03*
Y218500D03*
X648200Y440000D03*
X656164Y436538D03*
X651700Y453000D03*
X657700Y606900D03*
Y613400D03*
X681526Y99024D03*
Y103524D03*
X685276Y94934D03*
X685286Y107744D03*
X678200Y768500D03*
X686668Y797784D03*
Y807484D03*
Y802484D03*
X707700Y59500D03*
Y72500D03*
Y68000D03*
X722700Y197500D03*
Y193500D03*
X725400Y209000D03*
X729168Y797484D03*
X727700Y887000D03*
Y882500D03*
Y899000D03*
X749200Y82500D03*
Y88500D03*
Y94500D03*
Y99500D03*
X756416Y116784D03*
Y112284D03*
X753164Y476038D03*
X772200Y668000D03*
X770200Y858000D03*
Y853500D03*
X758200Y874500D03*
X786200Y546500D03*
X786700Y553500D03*
Y561000D03*
X779200Y644500D03*
X795794Y570468D03*
Y574968D03*
Y579468D03*
X809974Y469578D03*
X821200Y853500D03*
X851200Y715500D03*
X860341Y706312D03*
X882200Y334500D03*
Y338500D03*
X946794Y51797D03*
X948200Y59500D03*
X939150Y452700D03*
X1015200Y907000D03*
X1015416Y902468D03*
X1033200Y128500D03*
X1030200Y168500D03*
Y173000D03*
X1031474Y199578D03*
Y204578D03*
Y209578D03*
X1049200Y681000D03*
Y693000D03*
Y685000D03*
Y697000D03*
Y709000D03*
Y701000D03*
Y705000D03*
X1063668Y219284D03*
X1063700Y215000D03*
X1081200Y631500D03*
Y627500D03*
Y644000D03*
Y635500D03*
Y648000D03*
Y656000D03*
Y652000D03*
Y661500D03*
Y675500D03*
Y671500D03*
X1069700Y668000D03*
Y673000D03*
X1081200Y667500D03*
Y679500D03*
Y691500D03*
Y687500D03*
Y695500D03*
Y683500D03*
Y711500D03*
Y699500D03*
Y707500D03*
Y703500D03*
Y715500D03*
Y722500D03*
Y726500D03*
Y730500D03*
X1096168Y867284D03*
Y871784D03*
X1142200Y262500D03*
Y270500D03*
Y258500D03*
Y266500D03*
X1142168Y286284D03*
X1142200Y278500D03*
X1149700Y597000D03*
X1141700Y827000D03*
X1151200Y818000D03*
X1176700Y621000D03*
X1205700Y749000D03*
X1225700Y722500D03*
Y740500D03*
X1232200Y762000D03*
Y757500D03*
Y753000D03*
X1247377Y255000D03*
Y259500D03*
X1248200Y451500D03*
Y456000D03*
X1240700Y729500D03*
X1264200Y30000D03*
X1257188Y235000D03*
X1261200Y577000D03*
X1253700Y671000D03*
Y684000D03*
X1262700Y779000D03*
X1276700Y674500D03*
Y681000D03*
X1308700Y316500D03*
X1316200Y318000D03*
X1316317Y559912D03*
Y564412D03*
Y568912D03*
Y581912D03*
X1316400Y573000D03*
X1316317Y590912D03*
Y607912D03*
Y621412D03*
Y616912D03*
X1342317Y623912D03*
X1357700Y448000D03*
G54D52*
X152000Y465300D03*
X173943Y537396D03*
X197200Y431500D03*
X190200Y848000D03*
X317193Y450373D03*
X318223Y483783D03*
X333129Y241500D03*
X382700Y947000D03*
X469255Y301500D03*
Y305500D03*
X576700Y66000D03*
Y62000D03*
X628200Y575000D03*
X673786Y107874D03*
X686948Y122500D03*
X691162Y455464D03*
X709700Y568000D03*
X716200Y864000D03*
X771974Y475078D03*
X781700Y355500D03*
X796974Y475078D03*
X819200Y368500D03*
X817700Y849500D03*
X849200Y385000D03*
X846200Y638500D03*
X937650Y448700D03*
X1016700Y277500D03*
Y281500D03*
X1007700Y480500D03*
X1011916Y898468D03*
X1029700Y137000D03*
X1047200Y930000D03*
X1073629Y73758D03*
X1101700Y776500D03*
Y772500D03*
X1092668Y863284D03*
X1139700Y862000D03*
X1198668Y807784D03*
Y804284D03*
X1206700Y432500D03*
X1202200Y753000D03*
X1250200Y699500D03*
X1272200Y564500D03*
X1312817Y603912D03*
X1304700Y855000D03*
Y858500D03*
X1336700Y452000D03*
X1354200D03*
G54D25*
X40054Y829345D03*
X47554Y833220D03*
X40054Y837095D03*
X168495Y516875D03*
X175995Y520750D03*
X168495Y524625D03*
X198250Y789125D03*
Y796875D03*
Y810875D03*
Y803125D03*
X205750Y793000D03*
Y807000D03*
X278409Y430678D03*
X270909Y434553D03*
Y426803D03*
X757250Y461500D03*
X749750Y465375D03*
Y457625D03*
X1080518Y220224D03*
X1073018Y216349D03*
Y224099D03*
X1312260Y54737D03*
X1304760Y50862D03*
Y58612D03*
G54D109*
X600925Y44134D03*
X638917D03*
G54D145*
X1008268Y244094D03*
Y411417D03*
X1227166Y155511D03*
X1227165Y411417D03*
G54D154*
X1093861Y104842D03*
Y98242D03*
X1090061D03*
Y104842D03*
G54D163*
X1245921Y768500D03*
X1243953D03*
X1241984D03*
X1240016D03*
X1238047D03*
X1236079D03*
Y782500D03*
X1238047D03*
X1240016D03*
X1241984D03*
X1243953D03*
X1245921D03*
G54D136*
X787758Y445022D03*
X785790D03*
Y457134D03*
X787758D03*
X1342984Y430444D03*
X1341016D03*
Y442556D03*
X1342984D03*
G54D118*
X674931Y446821D03*
X672962D03*
X670993D03*
X669025D03*
X667056D03*
X665088D03*
X663119D03*
Y466107D03*
X665088D03*
X667056D03*
X669025D03*
X670993D03*
X672962D03*
X674931D03*
X682805Y446821D03*
X680836D03*
X678868D03*
X676899D03*
Y466107D03*
X678868D03*
X680836D03*
X682805D03*
X1050937Y145641D03*
X1048968D03*
X1046999D03*
X1045031D03*
X1043062D03*
X1041094D03*
X1039125D03*
Y164927D03*
X1041094D03*
X1043062D03*
X1045031D03*
X1046999D03*
X1048968D03*
X1050937D03*
X1058811Y145641D03*
X1056842D03*
X1054874D03*
X1052905D03*
Y164927D03*
X1054874D03*
X1056842D03*
X1058811D03*
X1265531Y434641D03*
X1263562D03*
X1261594D03*
X1259625D03*
Y453927D03*
X1261594D03*
X1263562D03*
X1265531D03*
X1279311Y434641D03*
X1277342D03*
X1275374D03*
X1273405D03*
X1271437D03*
X1269468D03*
X1267499D03*
Y453927D03*
X1269468D03*
X1271437D03*
X1273405D03*
X1275374D03*
X1277342D03*
X1279311D03*
G54D172*
X1332967Y585538D03*
Y601286D03*
X1356267Y585538D03*
Y601286D03*
G54D127*
X737200Y56165D03*
Y63840D03*
Y61280D03*
Y58720D03*
X747800Y56165D03*
Y58720D03*
Y61280D03*
Y63840D03*
G54D43*
X121890Y269528D03*
X131890D03*
X141890D03*
X1346396Y21656D03*
X1338526D03*
X1346396Y29526D03*
X1338526D03*
X1362146Y21656D03*
X1354271D03*
X1362146Y29526D03*
X1354271D03*
X1377896Y21656D03*
X1370021D03*
X1377896Y29526D03*
X1370021D03*
X1385766Y21656D03*
Y29526D03*
G54D70*
X227000Y858000D03*
X217000Y858500D03*
X222000Y853500D03*
Y858500D03*
Y863500D03*
X663500Y452000D03*
X672500D03*
X663500Y456000D03*
Y460500D03*
X667500Y454000D03*
Y458500D03*
X672500Y456000D03*
Y460500D03*
X681000Y452000D03*
Y456000D03*
Y460500D03*
X676500Y454000D03*
Y458500D03*
X713716Y121284D03*
X721716Y112784D03*
Y116784D03*
X717716Y121284D03*
X721716D03*
Y129284D03*
Y125284D03*
X729716Y121284D03*
X725716D03*
X788600Y449300D03*
X784800D03*
X784900Y453000D03*
X788800D03*
X852000Y401500D03*
X842000D03*
X847000Y396500D03*
Y401500D03*
Y406500D03*
X1031500Y884500D03*
X1035216Y884468D03*
X1035000Y888500D03*
Y880500D03*
X1039468Y155284D03*
X1048968D03*
X1053500Y153000D03*
X1044000D03*
X1048968Y150784D03*
X1039500Y151000D03*
X1048968Y159284D03*
X1039500Y159500D03*
X1053500Y157500D03*
X1044000D03*
X1039000Y884500D03*
X1057968Y155284D03*
X1058000Y150500D03*
Y159500D03*
X1116468Y870284D03*
Y874284D03*
Y865784D03*
X1112468Y870284D03*
X1120468D03*
X1259968Y444284D03*
X1260000Y448500D03*
X1264500Y446500D03*
X1260000Y440000D03*
X1264500Y442000D03*
X1278500Y448500D03*
Y444000D03*
X1274000Y447000D03*
X1269468Y444284D03*
Y448284D03*
X1278500Y439500D03*
X1269468Y439784D03*
X1274000Y442000D03*
X1344000Y434500D03*
X1340200D03*
Y438300D03*
X1343900Y438500D03*
X1344617Y588712D03*
Y593412D03*
X1349317D03*
G54D61*
X189800Y861000D03*
X193300Y852000D03*
X193800Y874000D03*
X215300Y816500D03*
X458229Y101500D03*
X602198Y426116D03*
Y431116D03*
Y441116D03*
Y436116D03*
Y451116D03*
Y446116D03*
X676548Y56500D03*
Y63500D03*
X725000Y202000D03*
X769574Y441078D03*
X852300Y720000D03*
X875768Y709784D03*
X1044300Y105500D03*
Y111000D03*
X1106300Y780500D03*
X1152700Y604700D03*
X1254800Y716000D03*
X1293300Y363000D03*
X1308300Y564500D03*
X1330800Y420000D03*
X1317417Y577412D03*
X1342417Y562412D03*
G54D35*
X63304Y717920D03*
X55304Y753920D03*
X63272Y797704D03*
X58772D03*
X67772D03*
X81304Y717920D03*
X69804Y843420D03*
X96772Y717704D03*
X92772D03*
X87804Y843420D03*
X103804Y762920D03*
X102304Y890420D03*
X127654Y312153D03*
X179500Y865700D03*
X189555Y570200D03*
X194500Y864700D03*
X199000Y887200D03*
X210000Y832700D03*
X212000Y887200D03*
X232000Y832700D03*
X228000D03*
X220000D03*
X224000D03*
X216000Y887200D03*
X225000Y890700D03*
X229500D03*
X234623Y569383D03*
X273500Y201200D03*
X313485Y248572D03*
X312555Y442700D03*
X317985Y248572D03*
X341000Y97700D03*
X347000Y116129D03*
X357429Y250200D03*
X361929D03*
X352929D03*
X361178Y985700D03*
X366429Y250200D03*
X375429D03*
X370929D03*
X379929D03*
X376000Y873200D03*
X371500D03*
X380000Y922200D03*
X375500D03*
X373678Y985700D03*
X386555Y302700D03*
X395555D03*
X384500Y873700D03*
X384000Y922200D03*
X412500Y268700D03*
X396929Y257200D03*
X400555Y302700D03*
X405555D03*
X409555D03*
X398000Y873700D03*
X424929Y253100D03*
X420429D03*
X424929Y261100D03*
X423055Y297200D03*
X418555Y302700D03*
X414055D03*
X434540Y109700D03*
X440000Y239700D03*
X433929Y261100D03*
X444778Y808700D03*
X438278D03*
X444278Y879200D03*
X458555Y296700D03*
X450778Y879200D03*
X475778Y808700D03*
X469278D03*
X473778Y879200D03*
X480278D03*
X549000Y154700D03*
X549055Y330700D03*
X558955Y371600D03*
X554955D03*
X571000Y154700D03*
X659462Y484164D03*
X682382Y126142D03*
X686432Y129712D03*
X678222Y126292D03*
X690512Y129652D03*
X704716Y151984D03*
X698968Y782684D03*
X704000Y888200D03*
X724532Y57416D03*
X720032Y65416D03*
X715716Y90484D03*
X715468Y758184D03*
X736248Y152200D03*
X731716Y151984D03*
X725748Y184200D03*
X726000Y894700D03*
X763000Y459200D03*
X767000D03*
Y475200D03*
X765998Y711254D03*
X770498D03*
X788774Y478778D03*
X779774D03*
X780500Y884700D03*
X785000D03*
X806000Y731700D03*
X838055Y273700D03*
X833555D03*
X847055D03*
X851555D03*
X856055D03*
X842555D03*
X866500Y104200D03*
X865055Y273700D03*
X860555D03*
X868820Y360080D03*
X863820D03*
X867000Y436200D03*
X862500D03*
X869468Y704984D03*
X879500Y91200D03*
X873468Y704984D03*
X919000Y55200D03*
X998000Y484200D03*
X1003000D03*
X999000Y540200D03*
X1003000D03*
X1010500Y455200D03*
X1011000Y500200D03*
X1017000Y540200D03*
X1013000D03*
X1029500Y124200D03*
X1025500Y136700D03*
X1035000Y178700D03*
X1027716Y911168D03*
X1032216D03*
X1039500Y178700D03*
X1070478Y753424D03*
X1074968Y753384D03*
X1070098Y761284D03*
X1093961Y103242D03*
X1089961D03*
X1089500Y412200D03*
X1088000Y457700D03*
X1092500D03*
X1087988Y745324D03*
X1101968Y809984D03*
X1117500Y617700D03*
X1103000Y637700D03*
X1107000D03*
X1115000D03*
X1111000Y745700D03*
X1107468Y809784D03*
X1106500Y837200D03*
X1122000Y617700D03*
X1149934Y584872D03*
X1137500Y625700D03*
X1151500Y630200D03*
X1146500Y625700D03*
X1146000Y637700D03*
X1151500D03*
X1135468Y861984D03*
X1159500Y623700D03*
X1179000Y403700D03*
X1172000Y757200D03*
X1180000D03*
X1184000D03*
X1176000D03*
X1191000Y403700D03*
X1195000D03*
X1189000Y745700D03*
X1192000Y757200D03*
X1213000Y634200D03*
X1209000D03*
X1205000D03*
X1201000D03*
X1201968Y764484D03*
X1215716Y809168D03*
X1211216D03*
X1207000Y809200D03*
X1215500Y855200D03*
X1201500D03*
X1226500Y443700D03*
X1225500Y793200D03*
X1220000Y809200D03*
X1246500Y468700D03*
X1242000D03*
X1238100Y857300D03*
X1257000Y39700D03*
X1271500Y548700D03*
X1276000Y663700D03*
X1281000Y709200D03*
X1277000Y719700D03*
X1295500Y34200D03*
X1284500Y318200D03*
X1293968Y662984D03*
X1285000Y663200D03*
X1310500Y43200D03*
X1314500D03*
X1299968Y661484D03*
X1303784Y789232D03*
X1308784D03*
X1314284D03*
X1312500Y857450D03*
X1307468Y916984D03*
X1301968D03*
X1312468D03*
X1327000Y332200D03*
X1323500Y448700D03*
Y436700D03*
X1332117Y622112D03*
X1327617D03*
X1328968Y676484D03*
X1326000Y857450D03*
X1317000D03*
X1321500D03*
X1316968Y916984D03*
X1332500Y54200D03*
X1336500Y138700D03*
X1338500Y459700D03*
X1347468Y456484D03*
X1352000Y81700D03*
X1363117Y565612D03*
X1354417Y623112D03*
G54D17*
X23104Y840720D03*
X23100Y854200D03*
X48104Y842720D03*
X62604Y830720D03*
X74604Y889720D03*
X89072Y770504D03*
X89104Y790220D03*
Y798220D03*
Y806720D03*
Y811220D03*
X135300Y666500D03*
X137604Y808220D03*
Y803720D03*
Y799720D03*
Y812720D03*
X149300Y844000D03*
X165100Y457800D03*
X152100Y469800D03*
X161855Y530000D03*
X153855D03*
X159855Y550500D03*
X157800Y666500D03*
X181855Y525500D03*
X182043Y537396D03*
X187100Y474800D03*
X190800Y869500D03*
X207823Y521183D03*
X212300Y812000D03*
X218355Y560000D03*
Y564500D03*
X237300Y423000D03*
Y427000D03*
X243800Y855500D03*
Y859500D03*
Y847500D03*
X291459Y419678D03*
X320800Y98000D03*
X315805Y313152D03*
X315729Y334500D03*
X314729Y348500D03*
Y354000D03*
X341229Y237500D03*
X361605Y405270D03*
Y410000D03*
Y414500D03*
Y419000D03*
X356323Y463783D03*
X355323Y473783D03*
Y478283D03*
X356235Y468450D03*
X355323Y482783D03*
X375855Y330500D03*
Y335000D03*
Y339500D03*
Y344000D03*
Y357500D03*
Y362000D03*
X398800Y265400D03*
X402300Y885000D03*
X407300Y915500D03*
Y911500D03*
X425800Y236500D03*
X423055Y283200D03*
Y279200D03*
X427300Y941500D03*
Y945500D03*
X454800Y117500D03*
X462300Y185000D03*
X596800Y200500D03*
Y205000D03*
Y214000D03*
Y218500D03*
X644800Y440000D03*
X652764Y436538D03*
X648300Y453000D03*
X654300Y606900D03*
Y613400D03*
X674800Y768500D03*
X678126Y99024D03*
Y103524D03*
X681876Y94934D03*
X681886Y107744D03*
X683268Y797784D03*
Y807484D03*
Y802484D03*
X704300Y59500D03*
Y72500D03*
Y68000D03*
X719300Y197500D03*
Y193500D03*
X722000Y209000D03*
X724300Y887000D03*
Y882500D03*
Y899000D03*
X725768Y797484D03*
X745800Y82500D03*
Y88500D03*
Y94500D03*
Y99500D03*
X753016Y116784D03*
Y112284D03*
X749764Y476038D03*
X754800Y874500D03*
X768800Y668000D03*
X766800Y858000D03*
Y853500D03*
X782800Y546500D03*
X783300Y553500D03*
Y561000D03*
X775800Y644500D03*
X806574Y469578D03*
X792394Y570468D03*
Y574968D03*
Y579468D03*
X817800Y853500D03*
X847800Y715500D03*
X856941Y706312D03*
X878800Y334500D03*
Y338500D03*
X935750Y452700D03*
X943394Y51797D03*
X944800Y59500D03*
X1011800Y907000D03*
X1012016Y902468D03*
X1029800Y128500D03*
X1026800Y168500D03*
Y173000D03*
X1028074Y199578D03*
Y204578D03*
Y209578D03*
X1045800Y681000D03*
Y693000D03*
Y685000D03*
Y697000D03*
Y709000D03*
Y701000D03*
Y705000D03*
X1060268Y219284D03*
X1060300Y215000D03*
X1066300Y668000D03*
Y673000D03*
X1077800Y631500D03*
Y627500D03*
Y644000D03*
Y635500D03*
Y648000D03*
Y656000D03*
Y652000D03*
Y661500D03*
Y675500D03*
Y671500D03*
Y667500D03*
Y679500D03*
Y691500D03*
Y687500D03*
Y695500D03*
Y683500D03*
Y711500D03*
Y699500D03*
Y707500D03*
Y703500D03*
Y715500D03*
Y722500D03*
Y726500D03*
Y730500D03*
X1092768Y867284D03*
Y871784D03*
X1138800Y262500D03*
Y270500D03*
Y258500D03*
Y266500D03*
X1138768Y286284D03*
X1138800Y278500D03*
X1146300Y597000D03*
X1138300Y827000D03*
X1147800Y818000D03*
X1173300Y621000D03*
X1202300Y749000D03*
X1222300Y722500D03*
Y740500D03*
X1228800Y762000D03*
Y757500D03*
Y753000D03*
X1243977Y255000D03*
Y259500D03*
X1244800Y451500D03*
Y456000D03*
X1237300Y729500D03*
X1260800Y30000D03*
X1253788Y235000D03*
X1257800Y577000D03*
X1250300Y671000D03*
Y684000D03*
X1259300Y779000D03*
X1273300Y674500D03*
Y681000D03*
X1312800Y318000D03*
X1305300Y316500D03*
X1312917Y559912D03*
Y564412D03*
Y568912D03*
Y581912D03*
X1313000Y573000D03*
X1312917Y590912D03*
Y607912D03*
Y621412D03*
Y616912D03*
X1338917Y623912D03*
X1354300Y448000D03*
G54D44*
X127654Y303753D03*
X190500Y889800D03*
X212500Y807300D03*
X203500Y889800D03*
X220500D03*
X274000Y915800D03*
X269000D03*
X295500Y130300D03*
X306400Y75200D03*
X301400D03*
X302159Y430478D03*
X332500Y941400D03*
X348000Y87300D03*
X353000Y76800D03*
X348000Y76300D03*
X392000Y45300D03*
X659462Y495264D03*
X687968Y776784D03*
X727968Y774784D03*
X784274Y481378D03*
X775500Y710800D03*
X806274Y459878D03*
X1018500Y501800D03*
X1026500Y147300D03*
X1052100Y182400D03*
X1095000Y757800D03*
X1175177Y231800D03*
X1190500Y233300D03*
X1263700Y473000D03*
X1324000Y55800D03*
X1347000Y83800D03*
X1343000Y461800D03*
X1362500Y443800D03*
Y454800D03*
G54D53*
X159555Y536250D03*
X163430Y543750D03*
X155680D03*
X764000Y653250D03*
X767875Y660750D03*
X760125D03*
X869987Y82376D03*
X866112Y89876D03*
X870625Y461750D03*
X873862Y89876D03*
X874500Y454250D03*
X878375Y461750D03*
X905625Y60750D03*
X909500Y53250D03*
X913375Y60750D03*
X1095500Y436750D03*
X1099375Y444250D03*
X1091625D03*
X1339000Y112250D03*
X1342875Y119750D03*
X1335125D03*
X1354000Y112250D03*
X1357875Y119750D03*
X1350125D03*
G54D146*
X1017000Y70081D03*
Y58919D03*
G54D80*
X302750Y18000D03*
X318250D03*
G54D62*
X196800Y905710D03*
Y913310D03*
X204900Y905710D03*
Y913310D03*
X267500Y204800D03*
Y197200D03*
X307485Y250672D03*
Y243072D03*
X324485Y251172D03*
Y243572D03*
X328429Y320300D03*
Y312700D03*
Y327200D03*
Y334800D03*
Y341700D03*
Y349300D03*
Y356200D03*
Y363800D03*
X318555Y436200D03*
X326555D03*
X318555Y443800D03*
X326555D03*
X336429Y320300D03*
Y312700D03*
Y327200D03*
Y334800D03*
Y341700D03*
Y349300D03*
Y356200D03*
Y363800D03*
X385500Y37600D03*
Y45200D03*
X579882Y269700D03*
Y277300D03*
X640500Y395700D03*
Y403300D03*
X648500Y395700D03*
Y403300D03*
X657000Y395700D03*
Y403300D03*
X692962Y450264D03*
Y442664D03*
X787000Y725200D03*
Y732800D03*
X802824Y336248D03*
Y343848D03*
X811838Y435740D03*
X820438D03*
X811838Y443340D03*
X820438D03*
X1028500Y254200D03*
X1036500D03*
X1028500Y261800D03*
X1036500D03*
X1045968Y172984D03*
Y180584D03*
X1066500Y173200D03*
Y180800D03*
X1084000Y148800D03*
Y141200D03*
X1083000Y173200D03*
X1072000Y165800D03*
Y158200D03*
X1080000Y165800D03*
Y158200D03*
X1074500Y173200D03*
X1083000Y180800D03*
X1074500D03*
X1085468Y882484D03*
Y890084D03*
X1088500Y753700D03*
Y761300D03*
X1103500Y787200D03*
Y794800D03*
X1093468Y882484D03*
Y890084D03*
X1114468Y248484D03*
Y256084D03*
X1128500Y825700D03*
Y833300D03*
X1141468Y876484D03*
X1149468D03*
X1141468Y884084D03*
X1149468D03*
X1157468Y876484D03*
X1165468D03*
X1157468Y884084D03*
X1165468D03*
X1257468Y466484D03*
Y474084D03*
X1277500Y462700D03*
Y470300D03*
X1293500Y446200D03*
Y453800D03*
Y462700D03*
X1285500D03*
X1293500Y470300D03*
X1285500D03*
X1302000Y462700D03*
Y470300D03*
X1366500Y429800D03*
Y422200D03*
X1374500Y429800D03*
Y422200D03*
G54D119*
X671500Y516250D03*
Y531750D03*
G54D155*
X1095006Y745402D03*
Y738906D03*
X1104230Y745402D03*
Y738906D03*
G54D128*
X730940Y205035D03*
X733500D03*
X736060D03*
Y196965D03*
X733500D03*
X730940D03*
G54D71*
X224297Y905248D03*
X230703D03*
G54D137*
X774938Y685354D03*
X777498D03*
X780058D03*
Y692754D03*
X777498D03*
X774938D03*
X868936Y687711D03*
X871496D03*
Y695111D03*
X868936D03*
X874056Y687711D03*
Y695111D03*
X1064208Y201524D03*
X1066768D03*
Y208924D03*
X1064208D03*
X1069328Y201524D03*
Y208924D03*
G54D173*
X1333317Y587506D03*
Y589475D03*
Y591443D03*
Y593412D03*
Y595381D03*
Y597349D03*
Y599318D03*
X1355917Y597349D03*
Y595381D03*
Y593412D03*
Y591443D03*
Y589475D03*
Y587506D03*
Y599318D03*
G54D26*
X48004Y849720D03*
X149200Y848000D03*
X225200Y883500D03*
X243700Y851500D03*
X312723Y497183D03*
Y524683D03*
X341129Y241500D03*
X339455Y449840D03*
X355223Y486783D03*
X433700Y268500D03*
X559700Y252500D03*
X563755Y328500D03*
X648200Y457000D03*
X758700Y67500D03*
X792294Y583468D03*
X801700Y860500D03*
Y856000D03*
X845700Y868500D03*
X869700Y409500D03*
X876700Y636500D03*
X927200Y51500D03*
X1011916Y879968D03*
X1037700Y124000D03*
X1052700Y287500D03*
X1052424Y291756D03*
Y296156D03*
X1052400Y299600D03*
X1048416Y900968D03*
X1064200Y737500D03*
X1054200Y844500D03*
X1113200Y817000D03*
X1138668Y282284D03*
X1147700Y814000D03*
X1138200Y822500D03*
X1147700D03*
X1207200Y878500D03*
X1249700Y197500D03*
Y201500D03*
Y205500D03*
X1248200Y435500D03*
X1281700Y564500D03*
X1369817Y593912D03*
G54D164*
X1241000Y775500D03*
G54D81*
X303250Y81500D03*
X818024Y465078D03*
X1027750Y155000D03*
X1249750Y445000D03*
G54D156*
X1159934Y573276D03*
Y589068D03*
X1179934Y573276D03*
Y589068D03*
G54D63*
X214800Y823000D03*
X207200D03*
X244700Y841500D03*
X252300D03*
X274800Y188500D03*
X267200D03*
X274800Y180500D03*
X267200D03*
X314785Y227872D03*
X307185D03*
X314785Y235872D03*
X307185D03*
X313205Y319652D03*
X313129Y328500D03*
X313629Y342000D03*
X306729D03*
X299129D03*
X313629Y360500D03*
X322685Y235872D03*
X330285D03*
X322685Y227872D03*
X330285D03*
X320805Y319652D03*
X320729Y328500D03*
X321229Y342000D03*
Y360500D03*
X375200Y66000D03*
X367600D03*
X396700Y271400D03*
X405129Y251400D03*
X412729D03*
X404300Y271400D03*
X405129Y259400D03*
X412729D03*
X573300Y431500D03*
X565700D03*
X573300Y439500D03*
X565700D03*
X595598Y386616D03*
X603198D03*
X595598Y377616D03*
X603198D03*
X595598Y395116D03*
X603198D03*
X595598Y403616D03*
X603198D03*
X595598Y419616D03*
X603198D03*
X595598Y411616D03*
X603198D03*
X619700Y413000D03*
X627300D03*
X619700Y429000D03*
X627300D03*
X619700Y421000D03*
X627300D03*
X619700Y437000D03*
X627300D03*
X687966Y88544D03*
X680366D03*
X685186Y114964D03*
X677586D03*
X681662Y479464D03*
X689262D03*
X681662Y487464D03*
X689262D03*
X681662Y495464D03*
X689262D03*
X681700Y511500D03*
X689300D03*
X681662Y503464D03*
X689262D03*
X681700Y519500D03*
X689300D03*
X771574Y448078D03*
X763974D03*
X786300Y361500D03*
X778700D03*
X786300Y369500D03*
X778700D03*
X786300Y377500D03*
X778700D03*
X786300Y385500D03*
X778700D03*
X824300Y382000D03*
X816700D03*
X824300Y374000D03*
X816700D03*
X824300Y398000D03*
X816700D03*
X824300Y390000D03*
X816700D03*
X855300Y370000D03*
X847700D03*
X855300Y378500D03*
X847700D03*
X852300Y726500D03*
X844700D03*
X1000200Y69500D03*
X1007800D03*
X1052700Y858500D03*
Y850500D03*
Y874500D03*
Y866500D03*
X1045416Y906968D03*
X1053016D03*
X1045416Y914968D03*
X1053016D03*
X1060300Y858500D03*
Y850500D03*
Y874500D03*
Y866500D03*
X1257200Y570500D03*
X1264800D03*
X1298168Y434784D03*
X1305768D03*
X1325300Y427000D03*
X1317700D03*
X1364700Y380000D03*
Y388000D03*
X1372300Y380000D03*
Y388000D03*
G54D138*
X789968Y743784D03*
Y763784D03*
X804968Y743784D03*
X799968D03*
X794968D03*
Y763784D03*
X799968D03*
X804968D03*
X870500Y720500D03*
X865500D03*
X860500D03*
Y740500D03*
X865500D03*
X870500D03*
X875500Y720500D03*
Y740500D03*
X1151468Y225784D03*
X1146468D03*
X1141468D03*
Y245784D03*
X1146468D03*
X1151468D03*
X1156468Y225784D03*
Y245784D03*
X1313784Y801032D03*
X1308784D03*
X1303784D03*
Y821032D03*
X1308784D03*
X1313784D03*
X1318784Y801032D03*
Y821032D03*
X1348084Y282757D03*
Y319907D03*
X1353084Y282757D03*
X1358084D03*
X1363084D03*
Y319907D03*
X1358084D03*
X1353084D03*
X1368084Y282757D03*
X1373084D03*
X1378084D03*
Y319907D03*
X1373084D03*
X1368084D03*
X1383084Y282757D03*
Y319907D03*
G54D72*
X224297Y912750D03*
X230703D03*
G54D174*
X1348084Y282053D03*
Y320611D03*
X1363084Y282053D03*
X1358084D03*
X1353084D03*
Y320611D03*
X1358084D03*
X1363084D03*
X1378084Y282053D03*
X1373084D03*
X1368084D03*
Y320611D03*
X1373084D03*
X1378084D03*
X1383084Y282053D03*
Y320611D03*
G54D147*
X1035216Y874725D03*
X1032657D03*
X1030098D03*
Y894211D03*
X1032657D03*
X1035216D03*
X1040334Y874725D03*
X1037775D03*
Y894211D03*
X1040334D03*
G54D54*
X166200Y666500D03*
X310100Y56700D03*
Y51700D03*
Y61700D03*
X380200Y943000D03*
X432255Y290600D03*
X682700Y473000D03*
X759948Y123500D03*
X787974Y434078D03*
X784200Y897000D03*
X806474Y465078D03*
X876200Y330000D03*
X1050916Y277968D03*
X1050700Y283000D03*
X1067700Y141000D03*
X1079200Y412000D03*
X1091700Y61000D03*
Y66500D03*
X1110700Y280000D03*
X1140168Y252784D03*
X1145200Y592500D03*
X1146700Y827000D03*
X1181270Y777000D03*
X1222200Y452500D03*
X1248400Y209700D03*
X1249200Y675500D03*
X1276200Y569000D03*
X1286112Y434712D03*
X1304200Y363000D03*
X1344700Y420000D03*
X1348317Y562412D03*
G54D36*
X71804Y793920D03*
X175500Y906700D03*
X171500D03*
X190800Y467000D03*
X186800D03*
X238455Y565800D03*
X309500Y88200D03*
X328555Y506700D03*
X324555D03*
X347023Y505983D03*
X373500Y14700D03*
X377000D03*
X367500Y869700D03*
X380500Y14700D03*
X594500Y240200D03*
X651964Y440738D03*
X685748Y99700D03*
X683055Y262700D03*
X687055D03*
X706500Y859700D03*
X711500Y68200D03*
X714055Y262700D03*
X718055D03*
X724000Y478700D03*
X729748Y180700D03*
X738117Y544668D03*
X742517D03*
X743000Y571700D03*
X771000Y455700D03*
X806274Y438778D03*
X792774Y475278D03*
X849500Y432700D03*
X857500Y649200D03*
X904500Y67700D03*
X984260Y195207D03*
X988660D03*
X1097500Y789200D03*
X1118300Y753200D03*
X1110468Y846984D03*
X1122800Y753200D03*
X1150258Y753394D03*
X1156768Y753484D03*
X1164200Y753400D03*
X1173000Y386700D03*
X1209470Y565210D03*
X1226500Y432200D03*
X1242100Y821800D03*
X1254000Y692200D03*
X1250500D03*
X1273000Y716200D03*
X1358617Y562112D03*
X1371617D03*
X1367617D03*
G54D27*
X51604Y849720D03*
X152800Y848000D03*
X228800Y883500D03*
X247300Y851500D03*
X316323Y497183D03*
Y524683D03*
X344729Y241500D03*
X343055Y449840D03*
X358823Y486783D03*
X437300Y268500D03*
X563300Y252500D03*
X567355Y328500D03*
X651800Y457000D03*
X762300Y67500D03*
X795894Y583468D03*
X805300Y860500D03*
Y856000D03*
X849300Y868500D03*
X873300Y409500D03*
X880300Y636500D03*
X930800Y51500D03*
X1015516Y879968D03*
X1041300Y124000D03*
X1052016Y900968D03*
X1056300Y287500D03*
X1056024Y291756D03*
Y296156D03*
X1056000Y299600D03*
X1067800Y737500D03*
X1057800Y844500D03*
X1116800Y817000D03*
X1142268Y282284D03*
X1151300Y814000D03*
X1141800Y822500D03*
X1151300D03*
X1210800Y878500D03*
X1253300Y197500D03*
Y201500D03*
Y205500D03*
X1251800Y435500D03*
X1285300Y564500D03*
X1373417Y593912D03*
G54D18*
X23104Y845220D03*
Y849720D03*
X30104Y885720D03*
X55104Y830720D03*
X56104Y872720D03*
Y877720D03*
Y868220D03*
Y882220D03*
X74604Y885720D03*
X89104Y815220D03*
X99104Y882720D03*
X116454Y316453D03*
Y320953D03*
X101104Y844220D03*
X138300Y283500D03*
X136300Y312000D03*
X143300Y666500D03*
X137604Y791720D03*
Y783720D03*
X152100Y474300D03*
X172600Y457800D03*
X181855Y530000D03*
X190300Y840000D03*
Y844000D03*
Y856500D03*
X186800Y865500D03*
X190800Y878500D03*
X237300Y419000D03*
Y431000D03*
X243300Y835500D03*
X243800Y863500D03*
X260959Y425678D03*
Y430178D03*
Y434678D03*
X269300Y884500D03*
X312823Y507683D03*
X320800Y93500D03*
X317323Y464283D03*
Y459783D03*
X317293Y454373D03*
X318323Y479783D03*
Y475283D03*
X343800Y884500D03*
Y878500D03*
Y893000D03*
X361355Y385000D03*
Y376000D03*
Y380500D03*
Y371000D03*
X361615Y400500D03*
X361355Y394000D03*
Y389500D03*
X351300Y884500D03*
Y878500D03*
Y893000D03*
Y889000D03*
X375855Y312500D03*
Y317000D03*
Y321500D03*
Y326000D03*
Y348500D03*
Y353000D03*
Y366500D03*
Y371000D03*
Y375500D03*
X376823Y387783D03*
X375075Y403780D03*
X375105Y408500D03*
Y417500D03*
Y413000D03*
Y426500D03*
Y422000D03*
Y431000D03*
Y435500D03*
X402300Y880500D03*
X421300Y268000D03*
X423055Y287200D03*
Y275200D03*
X438840Y106000D03*
Y110000D03*
X431840Y117500D03*
X438800Y244000D03*
X446300Y106000D03*
Y110000D03*
Y114500D03*
X457800Y277500D03*
Y273000D03*
X459800Y282000D03*
X462729Y165500D03*
Y172500D03*
Y180500D03*
X462300Y197000D03*
X462229Y189500D03*
X462300Y286500D03*
X469355Y293800D03*
X596800Y209500D03*
Y223000D03*
Y227500D03*
X635800Y453000D03*
X628300Y579000D03*
Y588500D03*
Y584000D03*
X627800Y606900D03*
Y612900D03*
X652764Y432538D03*
X644800Y444500D03*
X648300Y448500D03*
X673966Y94544D03*
X691016Y137784D03*
X704300Y63500D03*
X698800Y863500D03*
X722832Y100532D03*
X709800Y576500D03*
Y582000D03*
Y572000D03*
X724300Y864000D03*
X731548Y189500D03*
X724800Y455500D03*
X736264Y558538D03*
Y563538D03*
X737800Y553500D03*
X740268Y768784D03*
X732768D03*
Y763984D03*
X725768Y806284D03*
Y801984D03*
X753800Y82500D03*
Y88500D03*
Y94500D03*
Y99500D03*
X749764Y471538D03*
X752300Y571000D03*
Y575500D03*
X758800Y51500D03*
Y55500D03*
Y59500D03*
Y63500D03*
X762800Y138500D03*
Y134000D03*
X762700Y144300D03*
X775800Y649000D03*
X776300Y668000D03*
X796800Y471000D03*
X795800Y546500D03*
Y553500D03*
Y561000D03*
X801800Y851000D03*
X821300Y873000D03*
X835300Y858000D03*
X869800Y414000D03*
Y404500D03*
X865800Y467500D03*
X856800Y711000D03*
X872800Y101500D03*
X873800Y467500D03*
X917300Y70500D03*
X908800D03*
X983574Y204578D03*
Y209578D03*
Y214578D03*
X994300Y496500D03*
X1029800Y133000D03*
X1028074Y214078D03*
X1025016Y866968D03*
X1037800Y119500D03*
Y128500D03*
X1045800Y713000D03*
X1062768Y227284D03*
X1060268Y223284D03*
X1064300Y733500D03*
Y741500D03*
X1075268Y200784D03*
X1099300Y428000D03*
X1125800Y278000D03*
X1129800Y618000D03*
X1138800Y274500D03*
X1137800Y618000D03*
X1139768Y858284D03*
X1181300Y237000D03*
Y244000D03*
Y248000D03*
X1192477Y238000D03*
Y242500D03*
Y247500D03*
Y252500D03*
X1192468Y264060D03*
Y268560D03*
X1186300Y359000D03*
Y363500D03*
X1200300Y605500D03*
X1188800Y875500D03*
X1214584Y432532D03*
X1213800Y444000D03*
X1213270Y568510D03*
X1214800Y735500D03*
Y731000D03*
X1222300Y718500D03*
Y735500D03*
Y731000D03*
X1221800Y831500D03*
X1247477Y241500D03*
Y245500D03*
X1244300Y268500D03*
Y272500D03*
X1248300Y431500D03*
Y427500D03*
X1240300Y593000D03*
Y598000D03*
X1245800Y661000D03*
X1244300Y762000D03*
X1253788Y221500D03*
Y226000D03*
Y230500D03*
X1250300Y643000D03*
Y647000D03*
Y639000D03*
Y635000D03*
Y651000D03*
Y657000D03*
X1257800Y661000D03*
Y657000D03*
Y651000D03*
X1250300Y667000D03*
X1257800Y667500D03*
X1250300Y680000D03*
Y688000D03*
Y707500D03*
Y703500D03*
Y711500D03*
X1259300Y783000D03*
X1261900Y835100D03*
X1312917Y586412D03*
Y595412D03*
Y612412D03*
Y599912D03*
X1327300Y298000D03*
Y293000D03*
X1343917Y567412D03*
X1338917Y619412D03*
X1358800Y106000D03*
X1354300Y456000D03*
X1369917Y589912D03*
Y585412D03*
Y597912D03*
Y602412D03*
Y611412D03*
Y606912D03*
G54D129*
X749700Y483000D03*
X755300Y481000D03*
Y485000D03*
X865700Y477000D03*
X871300Y475000D03*
Y479000D03*
G54D165*
X1258504Y329331D03*
Y368701D03*
X1272677Y349016D03*
G54D90*
X326385Y218372D03*
X328585D03*
X326385Y221872D03*
X328585D03*
X404829Y241900D03*
X407029D03*
X404829Y245400D03*
X407029D03*
X519423Y324783D03*
X521623D03*
X519423Y327283D03*
X521623D03*
X525423Y330283D03*
Y332783D03*
X514923Y332283D03*
X517123D03*
X514923Y334783D03*
X517123D03*
X515900Y343500D03*
X518100D03*
X515900Y346000D03*
X518100D03*
X515900Y348500D03*
X518100D03*
X515900Y351000D03*
X518100D03*
X515900Y353500D03*
X518100D03*
X515900Y356000D03*
X518100D03*
X515900Y359500D03*
X518100D03*
X515900Y362000D03*
X518100D03*
X527623Y330283D03*
Y332783D03*
G54D45*
X127654Y298153D03*
X190500Y884200D03*
X212500Y801700D03*
X203500Y884200D03*
X220500D03*
X274000Y910200D03*
X269000D03*
X295500Y124700D03*
X306400Y69600D03*
X301400D03*
X302159Y424878D03*
X332500Y935800D03*
X353000Y71200D03*
X348000Y70700D03*
Y81700D03*
X392000Y39700D03*
X659462Y489664D03*
X687968Y771184D03*
X727968Y769184D03*
X784274Y475778D03*
X775500Y705200D03*
X806274Y454278D03*
X1018500Y496200D03*
X1026500Y141700D03*
X1052100Y176800D03*
X1095000Y752200D03*
X1175177Y226200D03*
X1190500Y227700D03*
X1263700Y467400D03*
X1324000Y50200D03*
X1347000Y78200D03*
X1343000Y456200D03*
X1362500Y438200D03*
Y449200D03*
G54D91*
X332086Y408858D03*
X355708Y96456D03*
X450196Y257874D03*
X572243Y337992D03*
G54D175*
X1348595Y545800D03*
X1342639D03*
X1348595Y555024D03*
X1342639D03*
G54D28*
X45270Y901388D03*
X47770D03*
X50270D03*
Y921988D03*
X47770D03*
X45270D03*
X62637Y729959D03*
X65197D03*
Y752049D03*
X62637D03*
X66612Y808104D03*
X64052D03*
X61492D03*
X58932D03*
Y820904D03*
X61492D03*
X64052D03*
X66612D03*
X67453Y853207D03*
Y875297D03*
X52770Y901388D03*
X55270D03*
X57770D03*
X60270D03*
X62770D03*
X65270D03*
Y921988D03*
X62770D03*
X60270D03*
X57770D03*
X55270D03*
X52770D03*
X67757Y729959D03*
X70317D03*
X72872D03*
X75432D03*
X77992D03*
X80552D03*
X83112D03*
Y752049D03*
X80552D03*
X77992D03*
X75432D03*
X72872D03*
X70317D03*
X67757D03*
X70013Y853207D03*
X72573D03*
X75133D03*
X77688D03*
X80248D03*
X82808D03*
Y875297D03*
X80248D03*
X77688D03*
X75133D03*
X72573D03*
X70013D03*
X67770Y901388D03*
X70270D03*
X72770D03*
Y921988D03*
X70270D03*
X67770D03*
X85672Y729959D03*
X88227D03*
X90787D03*
X93347D03*
X95907D03*
Y752049D03*
X93347D03*
X90787D03*
X88227D03*
X85672D03*
X85368Y853207D03*
X87928D03*
X90488D03*
X93043D03*
X95603D03*
X98163D03*
Y875297D03*
X95603D03*
X93043D03*
X90488D03*
X87928D03*
X85368D03*
X100723Y853207D03*
Y875297D03*
X104054Y901420D03*
X106554D03*
X109054D03*
X111554D03*
X114054D03*
X116554D03*
Y922020D03*
X114054D03*
X111554D03*
X109054D03*
X106554D03*
X104054D03*
X119054Y901420D03*
X121554D03*
X124054D03*
X126554D03*
X129054D03*
X131554D03*
Y922020D03*
X129054D03*
X126554D03*
X124054D03*
X121554D03*
X119054D03*
X341250Y921700D03*
X343750D03*
X346250D03*
Y942300D03*
X343750D03*
X341250D03*
X348750Y921700D03*
X351250D03*
X353750D03*
X356250D03*
X358750D03*
X361250D03*
Y942300D03*
X358750D03*
X356250D03*
X353750D03*
X351250D03*
X348750D03*
X363750Y921700D03*
X366250D03*
X368750D03*
Y942300D03*
X366250D03*
X363750D03*
X393250Y922200D03*
X395750D03*
Y942800D03*
X393250D03*
X398250Y922200D03*
X400750D03*
X403250D03*
X405750D03*
X408250D03*
X410750D03*
Y942800D03*
X408250D03*
X405750D03*
X403250D03*
X400750D03*
X398250D03*
X413250Y922200D03*
X415750D03*
X418250D03*
X420750D03*
Y942800D03*
X418250D03*
X415750D03*
X413250D03*
X558495Y339988D03*
X555935D03*
X553375D03*
X550815D03*
Y356168D03*
X553375D03*
X555935D03*
X558495D03*
X994660Y513600D03*
X997220D03*
X999780D03*
X1002340D03*
Y526400D03*
X999780D03*
X997220D03*
X994660D03*
X1008660Y513600D03*
X1011220D03*
X1013780D03*
X1016340D03*
Y526400D03*
X1013780D03*
X1011220D03*
X1008660D03*
X1182660Y373910D03*
Y390090D03*
X1190340Y373910D03*
X1187780D03*
X1185220D03*
Y390090D03*
X1187780D03*
X1190340D03*
G54D64*
X215110Y848450D03*
Y868550D03*
X228890Y848450D03*
Y868550D03*
G54D148*
X1025473Y879350D03*
Y881909D03*
Y884468D03*
Y887027D03*
Y889586D03*
X1044959D03*
Y887027D03*
Y884468D03*
Y881909D03*
Y879350D03*
G54D157*
X1215256Y203150D03*
Y200000D03*
Y196851D03*
Y193701D03*
Y190552D03*
Y218898D03*
Y215748D03*
Y212599D03*
Y209449D03*
Y206300D03*
Y237796D03*
Y234646D03*
Y231496D03*
Y228347D03*
Y225197D03*
Y222048D03*
Y253544D03*
Y250394D03*
Y247245D03*
Y244095D03*
Y240945D03*
Y269292D03*
Y266142D03*
Y262993D03*
Y259843D03*
Y256693D03*
Y285040D03*
Y281890D03*
Y278741D03*
Y275591D03*
Y272441D03*
Y300788D03*
Y297638D03*
Y294489D03*
Y291339D03*
Y288189D03*
Y319685D03*
Y316536D03*
Y313386D03*
Y310237D03*
Y307087D03*
Y303937D03*
Y335434D03*
Y332284D03*
Y329134D03*
Y325985D03*
Y322835D03*
Y351182D03*
Y348032D03*
Y344882D03*
Y341733D03*
Y338583D03*
Y366930D03*
Y363780D03*
Y360630D03*
Y357481D03*
Y354331D03*
Y376378D03*
Y373229D03*
Y370079D03*
X1232776Y203150D03*
Y200000D03*
Y196851D03*
Y193701D03*
Y190552D03*
Y218898D03*
Y215748D03*
Y212599D03*
Y209449D03*
Y206300D03*
Y237796D03*
Y234646D03*
Y231496D03*
Y228347D03*
Y225197D03*
Y222048D03*
Y253544D03*
Y250394D03*
Y247245D03*
Y244095D03*
Y240945D03*
Y269292D03*
Y266142D03*
Y262993D03*
Y259843D03*
Y256693D03*
Y285040D03*
Y281890D03*
Y278741D03*
Y275591D03*
Y272441D03*
Y300788D03*
Y297638D03*
Y294489D03*
Y291339D03*
Y288189D03*
Y319685D03*
Y316536D03*
Y313386D03*
Y310237D03*
Y307087D03*
Y303937D03*
Y335434D03*
Y332284D03*
Y329134D03*
Y325985D03*
Y322835D03*
Y351182D03*
Y348032D03*
Y344882D03*
Y341733D03*
Y338583D03*
Y366930D03*
Y363780D03*
Y360630D03*
Y357481D03*
Y354331D03*
Y376378D03*
Y373229D03*
Y370079D03*
G54D55*
X175993Y544096D03*
X179743D03*
Y554696D03*
X175993D03*
X183493Y544096D03*
Y554696D03*
X1094250Y90300D03*
X1090500D03*
X1086750D03*
Y79700D03*
X1090500D03*
X1094250D03*
G54D73*
X234614Y891272D03*
X236386D03*
G54D37*
X71804Y797520D03*
X175500Y910300D03*
X171500D03*
X190800Y470600D03*
X186800D03*
X238455Y569400D03*
X309500Y91800D03*
X328555Y510300D03*
X324555D03*
X347023Y509583D03*
X373500Y18300D03*
X377000D03*
X367500Y873300D03*
X380500Y18300D03*
X594500Y243800D03*
X651964Y444338D03*
X685748Y103300D03*
X683055Y266300D03*
X687055D03*
X706500Y863300D03*
X711500Y71800D03*
X714055Y266300D03*
X718055D03*
X724000Y482300D03*
X729748Y184300D03*
X738117Y548268D03*
X742517D03*
X743000Y575300D03*
X771000Y459300D03*
X806274Y442378D03*
X792774Y478878D03*
X849500Y436300D03*
X857500Y652800D03*
X904500Y71300D03*
X984260Y198807D03*
X988660D03*
X1097500Y792800D03*
X1118300Y756800D03*
X1110468Y850584D03*
X1122800Y756800D03*
X1150258Y756994D03*
X1156768Y757084D03*
X1164200Y757000D03*
X1173000Y390300D03*
X1209470Y568810D03*
X1226500Y435800D03*
X1242100Y825400D03*
X1254000Y695800D03*
X1250500D03*
X1273000Y719800D03*
X1358617Y565712D03*
X1371617D03*
X1367617D03*
G54D19*
X26504Y845220D03*
Y849720D03*
X33504Y885720D03*
X58504Y830720D03*
X59504Y872720D03*
Y877720D03*
Y868220D03*
Y882220D03*
X78004Y885720D03*
X92504Y815220D03*
X104504Y844220D03*
X102504Y882720D03*
X119854Y316453D03*
Y320953D03*
X141700Y283500D03*
X139700Y312000D03*
X146700Y666500D03*
X141004Y791720D03*
Y783720D03*
X155500Y474300D03*
X176000Y457800D03*
X185255Y530000D03*
X193700Y840000D03*
Y844000D03*
Y856500D03*
X190200Y865500D03*
X194200Y878500D03*
X240700Y419000D03*
Y431000D03*
X246700Y835500D03*
X247200Y863500D03*
X264359Y425678D03*
Y430178D03*
Y434678D03*
X272700Y884500D03*
X324200Y93500D03*
X320723Y464283D03*
Y459783D03*
X320693Y454373D03*
X321723Y479783D03*
Y475283D03*
X316223Y507683D03*
X347200Y884500D03*
Y878500D03*
Y893000D03*
X354700Y884500D03*
Y878500D03*
Y893000D03*
Y889000D03*
X379255Y312500D03*
Y317000D03*
Y321500D03*
Y326000D03*
Y348500D03*
Y353000D03*
Y366500D03*
Y371000D03*
X364755Y385000D03*
Y376000D03*
Y380500D03*
Y371000D03*
X379255Y375500D03*
X365015Y400500D03*
X364755Y394000D03*
Y389500D03*
X378475Y403780D03*
X378505Y408500D03*
Y417500D03*
Y413000D03*
Y426500D03*
Y422000D03*
Y431000D03*
Y435500D03*
X380223Y387783D03*
X405700Y880500D03*
X424700Y268000D03*
X426455Y287200D03*
Y275200D03*
X442240Y106000D03*
Y110000D03*
X435240Y117500D03*
X442200Y244000D03*
X449700Y106000D03*
Y110000D03*
Y114500D03*
X461200Y277500D03*
Y273000D03*
X466129Y165500D03*
Y172500D03*
Y180500D03*
X465700Y197000D03*
X465629Y189500D03*
X465700Y286500D03*
X463200Y282000D03*
X472755Y293800D03*
X600200Y209500D03*
Y223000D03*
Y227500D03*
X639200Y453000D03*
X631700Y579000D03*
Y588500D03*
Y584000D03*
X631200Y606900D03*
Y612900D03*
X656164Y432538D03*
X648200Y444500D03*
X651700Y448500D03*
X677366Y94544D03*
X707700Y63500D03*
X694416Y137784D03*
X702200Y863500D03*
X713200Y576500D03*
Y582000D03*
Y572000D03*
X726232Y100532D03*
X734948Y189500D03*
X728200Y455500D03*
X739664Y558538D03*
Y563538D03*
X736168Y768784D03*
Y763984D03*
X729168Y806284D03*
Y801984D03*
X727700Y864000D03*
X757200Y82500D03*
Y88500D03*
Y94500D03*
Y99500D03*
X753164Y471538D03*
X741200Y553500D03*
X755700Y571000D03*
Y575500D03*
X743668Y768784D03*
X762200Y51500D03*
Y55500D03*
Y59500D03*
Y63500D03*
X766200Y138500D03*
Y134000D03*
X766100Y144300D03*
X779200Y649000D03*
X779700Y668000D03*
X800200Y471000D03*
X799200Y546500D03*
Y553500D03*
Y561000D03*
X805200Y851000D03*
X838700Y858000D03*
X824700Y873000D03*
X869200Y467500D03*
X860200Y711000D03*
X876200Y101500D03*
X873200Y414000D03*
Y404500D03*
X877200Y467500D03*
X920700Y70500D03*
X912200D03*
X986974Y204578D03*
Y209578D03*
Y214578D03*
X997700Y496500D03*
X1033200Y133000D03*
X1031474Y214078D03*
X1028416Y866968D03*
X1041200Y119500D03*
Y128500D03*
X1049200Y713000D03*
X1066168Y227284D03*
X1063668Y223284D03*
X1067700Y733500D03*
Y741500D03*
X1078668Y200784D03*
X1102700Y428000D03*
X1129200Y278000D03*
X1133200Y618000D03*
X1142200Y274500D03*
X1141200Y618000D03*
X1143168Y858284D03*
X1195877Y238000D03*
X1184700Y237000D03*
X1195877Y242500D03*
X1184700Y244000D03*
X1195877Y247500D03*
X1184700Y248000D03*
X1195877Y252500D03*
X1195868Y264060D03*
Y268560D03*
X1189700Y359000D03*
Y363500D03*
X1192200Y875500D03*
X1217200Y444000D03*
X1216670Y568510D03*
X1203700Y605500D03*
X1217984Y432532D03*
X1225700Y718500D03*
X1218200Y735500D03*
Y731000D03*
X1225700Y735500D03*
Y731000D03*
X1225200Y831500D03*
X1247700Y268500D03*
Y272500D03*
X1243700Y593000D03*
Y598000D03*
X1249200Y661000D03*
X1247700Y762000D03*
X1257188Y221500D03*
Y226000D03*
Y230500D03*
X1250877Y241500D03*
Y245500D03*
X1251700Y431500D03*
Y427500D03*
X1253700Y643000D03*
Y647000D03*
Y639000D03*
Y635000D03*
Y651000D03*
Y657000D03*
X1261200Y661000D03*
Y657000D03*
Y651000D03*
X1253700Y667000D03*
X1261200Y667500D03*
X1253700Y680000D03*
Y688000D03*
Y707500D03*
Y703500D03*
Y711500D03*
X1262700Y783000D03*
X1265300Y835100D03*
X1330700Y298000D03*
Y293000D03*
X1316317Y586412D03*
Y595412D03*
Y612412D03*
Y599912D03*
X1347317Y567412D03*
X1342317Y619412D03*
X1362200Y106000D03*
X1357700Y456000D03*
X1373317Y589912D03*
Y585412D03*
Y597912D03*
Y602412D03*
Y611412D03*
Y606912D03*
G54D82*
X305750Y81500D03*
X820524Y465078D03*
X1030250Y155000D03*
X1252250Y445000D03*
G54D166*
X1272441Y7087D03*
X1299213D03*
G54D46*
X132123Y318877D03*
X123654Y320953D03*
X360433Y131496D03*
Y134645D03*
X357284D03*
X360433Y137795D03*
X357284D03*
X360433Y216535D03*
X357284D03*
X360433Y219685D03*
X357284D03*
X360433Y222834D03*
X363583Y131496D03*
Y134645D03*
Y137795D03*
Y216535D03*
Y219685D03*
Y222834D03*
X442323Y131496D03*
Y134645D03*
Y137795D03*
Y216535D03*
Y219685D03*
Y222834D03*
X445473Y131496D03*
X448622Y134645D03*
X445473D03*
X448622Y137795D03*
X445473D03*
X448622Y216535D03*
X445473D03*
X448622Y219685D03*
X445473D03*
Y222834D03*
X1121397Y662363D03*
X1124547D03*
X1127696D03*
X1121397Y659213D03*
X1124547D03*
X1127696D03*
X1121397Y665512D03*
X1124547D03*
X1127696D03*
X1121397Y725355D03*
X1124547D03*
X1127696D03*
X1121397Y722205D03*
X1124547D03*
X1127696D03*
X1121397Y719056D03*
X1124547D03*
X1127696D03*
X1181240Y662363D03*
Y659213D03*
Y665512D03*
Y725355D03*
Y722205D03*
Y719056D03*
X1184389Y662363D03*
X1187539D03*
X1184389Y659213D03*
X1187539D03*
X1184389Y665512D03*
X1187539D03*
X1184389Y725355D03*
X1187539D03*
X1184389Y722205D03*
X1187539D03*
X1184389Y719056D03*
X1187539D03*
X1207500Y239500D03*
X1312750Y314000D03*
X1322500Y299000D03*
X1324000Y290500D03*
G54D139*
X805750Y363500D03*
X805250D03*
X1367750Y356500D03*
X1367250D03*
G54D167*
X1275984Y17914D03*
X1295670D03*
X1285827D03*
G54D158*
X1203830Y576840D03*
Y596840D03*
X1220370Y576840D03*
Y596840D03*
G54D149*
X1045000Y32598D03*
X1096732D03*
G54D92*
X339500Y35400D03*
Y57600D03*
G54D65*
X211950Y851610D03*
Y865390D03*
X232050Y851610D03*
Y865390D03*
G54D47*
X129600Y839160D03*
Y841720D03*
Y844280D03*
Y846840D03*
X142400Y844280D03*
Y841720D03*
Y839160D03*
Y846840D03*
X331623Y454943D03*
Y457503D03*
Y460063D03*
Y462623D03*
X331123Y476943D03*
Y479503D03*
Y482063D03*
Y484623D03*
X344423Y462623D03*
Y460063D03*
Y457503D03*
Y454943D03*
X343923Y482063D03*
Y479503D03*
Y476943D03*
Y484623D03*
X368900Y882420D03*
Y884980D03*
Y887540D03*
Y890100D03*
Y892660D03*
Y895220D03*
Y897780D03*
Y900340D03*
Y902900D03*
Y905460D03*
Y908020D03*
Y910580D03*
X391100Y892660D03*
Y890100D03*
Y887540D03*
Y884980D03*
Y882420D03*
Y910580D03*
Y908020D03*
Y905460D03*
Y902900D03*
Y900340D03*
Y897780D03*
Y895220D03*
X433765Y276060D03*
Y278620D03*
Y281180D03*
Y283740D03*
X449945D03*
Y281180D03*
Y278620D03*
Y276060D03*
X639874Y577738D03*
Y580298D03*
Y582858D03*
Y585418D03*
X652674Y580298D03*
Y577738D03*
Y585418D03*
Y582858D03*
X723600Y573160D03*
Y575720D03*
Y578280D03*
Y580840D03*
X736400D03*
Y578280D03*
Y575720D03*
Y573160D03*
X745400Y894120D03*
Y891560D03*
Y889000D03*
Y886440D03*
Y883880D03*
Y881325D03*
Y896675D03*
X765694Y573128D03*
Y575688D03*
Y578248D03*
Y580808D03*
X767600Y881325D03*
Y883880D03*
Y886440D03*
Y889000D03*
Y891560D03*
Y894120D03*
Y896675D03*
X778494Y580808D03*
Y578248D03*
Y575688D03*
Y573128D03*
G54D74*
X235500Y887728D03*
G54D56*
X181055Y565550D03*
X178496D03*
X181055Y573450D03*
X178496D03*
X183614Y565550D03*
Y573450D03*
X390988Y248050D03*
X388429D03*
X385870D03*
X390988Y255950D03*
X388429D03*
X385870D03*
G54D176*
X1336743Y581762D03*
Y605062D03*
X1352491Y581762D03*
Y605062D03*
G54D29*
X39804Y931420D03*
X97500Y931200D03*
X153200Y660600D03*
X179000Y851700D03*
X180000Y906200D03*
X190000D03*
X185000D03*
X212500Y790700D03*
X343000Y67700D03*
X520000Y146200D03*
X687968Y760184D03*
X727968Y758184D03*
X793500Y727700D03*
X809000Y338200D03*
X810000Y474200D03*
X904500Y76200D03*
X1065500Y158700D03*
X1056700Y173200D03*
X1107968Y250984D03*
X1268468Y465984D03*
X1287000Y447200D03*
X1360000Y423700D03*
X1357500Y460700D03*
G54D38*
X97804Y803820D03*
X458000Y286500D03*
X547555Y364500D03*
X1197000Y366000D03*
X1219968Y790784D03*
X1312468Y902784D03*
X1379862Y108465D03*
Y119095D03*
G54D83*
X304500Y125700D03*
Y137300D03*
X318000Y125700D03*
Y137300D03*
X579500Y369800D03*
Y358200D03*
X593000Y369800D03*
Y358200D03*
X778824Y334248D03*
X792324D03*
X778824Y345848D03*
X792324D03*
X1030000Y58700D03*
Y70300D03*
X1057000Y58700D03*
X1043500D03*
X1057000Y70300D03*
X1043500D03*
G54D168*
X1279401Y38583D03*
X1268631D03*
G54D57*
X181055Y569500D03*
X388429Y252000D03*
G54D48*
X146364Y290190D03*
X135364D03*
X305100Y36200D03*
Y27500D03*
Y44800D03*
X316100Y36200D03*
Y27500D03*
Y44800D03*
X829500Y452500D03*
X840500D03*
X869000Y379500D03*
X880000D03*
X1038000Y80500D03*
Y89500D03*
Y98500D03*
X1049000Y80500D03*
Y89500D03*
Y98500D03*
X1054000Y923500D03*
X1043000D03*
X1283500Y371000D03*
Y380000D03*
X1294500Y371000D03*
Y380000D03*
X1313000Y371000D03*
X1302000D03*
X1313000Y380000D03*
X1302000D03*
X1362000Y371500D03*
Y362500D03*
X1373000Y371500D03*
Y362500D03*
G54D75*
X244000Y894000D03*
X249000D03*
X254000D03*
X259000D03*
X1050000Y260000D03*
X1045000D03*
X1060000D03*
X1055000D03*
G54D84*
X311085Y217872D03*
X308885D03*
X311085Y221372D03*
X308885D03*
X303529Y336000D03*
X301329D03*
X303529Y332000D03*
X301329D03*
X341640Y132500D03*
X339440D03*
X341640Y130000D03*
X339440D03*
X341640Y136500D03*
X339440D03*
X341640Y139000D03*
X339440D03*
X341640Y143000D03*
X339440D03*
X341640Y145500D03*
X339440D03*
X341640Y152000D03*
X339440D03*
X341640Y149500D03*
X339440D03*
X341640Y169000D03*
X339440D03*
X341640Y171500D03*
X339440D03*
X341640Y165000D03*
X339440D03*
X341640Y156000D03*
X339440D03*
X341640Y162500D03*
X339440D03*
X341640Y158500D03*
X339440D03*
X341640Y175500D03*
X339440D03*
X341640Y178000D03*
X339440D03*
G54D93*
X332000Y123900D03*
Y126100D03*
X334500Y123900D03*
Y126100D03*
X342429Y330900D03*
Y333100D03*
X346429Y330900D03*
Y333100D03*
X342429Y345400D03*
Y347600D03*
X345929Y345400D03*
Y347600D03*
Y358900D03*
Y361100D03*
X342429Y358900D03*
Y361100D03*
X343555Y439900D03*
Y442100D03*
X339555Y439900D03*
Y442100D03*
X335555Y439900D03*
Y442100D03*
X331555Y439900D03*
Y442100D03*
X359555Y439900D03*
Y442100D03*
X355555Y439900D03*
Y442100D03*
X351555Y439900D03*
Y442100D03*
X347555Y439900D03*
Y442100D03*
X367000Y439900D03*
Y442100D03*
X363555Y439900D03*
Y442100D03*
X407555Y448900D03*
Y451100D03*
X410055Y448900D03*
Y451100D03*
X400555Y448900D03*
Y451100D03*
X403055Y448900D03*
Y451100D03*
X428555Y448900D03*
Y451100D03*
X424055Y448900D03*
Y451100D03*
X421555Y448900D03*
Y451100D03*
X417055Y448900D03*
Y451100D03*
X414555Y448900D03*
Y451100D03*
X445055Y448900D03*
Y451100D03*
X442555Y448900D03*
Y451100D03*
X438055Y448900D03*
Y451100D03*
X435555Y448900D03*
Y451100D03*
X431055Y448900D03*
Y451100D03*
X459055Y448900D03*
Y451100D03*
X456555Y448900D03*
Y451100D03*
X452055Y448900D03*
Y451100D03*
X449555Y448900D03*
Y451100D03*
X477555Y448900D03*
Y451100D03*
X473055Y448900D03*
Y451100D03*
X470555Y448900D03*
Y451100D03*
X466055Y448900D03*
Y451100D03*
X463555Y448900D03*
Y451100D03*
X480055Y448900D03*
Y451100D03*
X518365Y388360D03*
Y390560D03*
X525055Y387900D03*
Y390100D03*
X522555Y387900D03*
Y390100D03*
X515865Y388360D03*
Y390560D03*
X539000Y387900D03*
Y390100D03*
X536500Y387900D03*
Y390100D03*
X532055Y387900D03*
Y390100D03*
X529555Y387900D03*
Y390100D03*
G54D159*
X1212840Y775850D03*
X1210280D03*
X1207720D03*
X1205160D03*
Y792150D03*
X1207720D03*
X1210280D03*
X1212840D03*
G54D39*
X117654Y301703D03*
X113779Y309203D03*
X121529D03*
X139191Y298593D03*
X143066Y306093D03*
X135316D03*
G54D66*
X212250Y853579D03*
Y855547D03*
Y857516D03*
Y859484D03*
Y861453D03*
Y863421D03*
X231750Y859484D03*
Y857516D03*
Y855547D03*
Y853579D03*
Y863421D03*
Y861453D03*
G54D177*
X1346586Y582112D03*
X1344617D03*
X1342648D03*
X1340680D03*
X1338711D03*
Y604712D03*
X1340680D03*
X1342648D03*
X1344617D03*
X1346586D03*
X1350523Y582112D03*
X1348554D03*
Y604712D03*
X1350523D03*
G54D169*
X1283596Y557000D03*
X1273404D03*
G54D67*
X214400Y912820D03*
Y898980D03*
G54D178*
X1344617Y593412D03*
G54D76*
X270078Y92125D03*
Y155117D03*
X490944Y79921D03*
Y255118D03*
X743897Y353543D03*
Y410629D03*
X1305117Y87548D03*
Y262745D03*
X1376968Y147243D03*
Y216535D03*
G54D85*
X330200Y9000D03*
Y20000D03*
X347600Y9000D03*
X338900D03*
X347600Y20000D03*
X338900D03*
X356300Y9000D03*
X365000D03*
X356300Y20000D03*
X365000D03*
X359000Y34000D03*
Y45000D03*
X377000Y34000D03*
X368000D03*
X377000Y45000D03*
X368000D03*
X1047500Y831500D03*
Y842500D03*
X1075500Y893500D03*
Y882500D03*
X1180500Y826000D03*
Y837000D03*
X1374500Y438500D03*
Y449500D03*
G54D94*
X332829Y248400D03*
X341029D03*
X332829Y262600D03*
X341029D03*
G54D58*
X171800Y666500D03*
X315700Y56700D03*
Y51700D03*
Y61700D03*
X385800Y943000D03*
X437855Y290600D03*
X688300Y473000D03*
X765548Y123500D03*
X789800Y897000D03*
X793574Y434078D03*
X812074Y465078D03*
X881800Y330000D03*
X1056516Y277968D03*
X1056300Y283000D03*
X1073300Y141000D03*
X1084800Y412000D03*
X1097300Y61000D03*
Y66500D03*
X1116300Y280000D03*
X1145768Y252784D03*
X1150800Y592500D03*
X1152300Y827000D03*
X1186870Y777000D03*
X1227800Y452500D03*
X1254000Y209700D03*
X1254800Y675500D03*
X1281800Y569000D03*
X1291712Y434712D03*
X1309800Y363000D03*
X1350300Y420000D03*
X1353917Y562412D03*
G54D49*
X143500Y680750D03*
X139625Y673250D03*
X147375D03*
X143500Y695960D03*
X139625Y688460D03*
X147375D03*
X163000Y680750D03*
X159125Y673250D03*
X166875D03*
X163000Y696460D03*
X159125Y688960D03*
X166875D03*
X747748Y187250D03*
X743873Y179750D03*
X751623D03*
X873125Y615472D03*
X880875D03*
X877000Y622972D03*
X1181125Y861750D03*
X1188875D03*
X1185000Y869250D03*
G54D86*
X331130Y72321D03*
Y68384D03*
X320714Y70353D03*
G54D179*
X1371572Y122170D03*
G54D68*
X226921Y848750D03*
X224953D03*
X222984D03*
X221016D03*
X219047D03*
X217079D03*
Y868250D03*
X219047D03*
X221016D03*
X222984D03*
X224953D03*
X226921D03*
G54D77*
X271500Y893500D03*
Y902500D03*
G54D59*
X200000Y391500D03*
Y401500D03*
Y411500D03*
Y421500D03*
X216500Y391500D03*
Y401500D03*
Y411500D03*
Y421500D03*
X1296000Y319500D03*
Y329500D03*
X1367067Y42323D03*
Y60039D03*
Y78544D03*
Y96260D03*
X1392657Y42323D03*
Y60039D03*
Y78544D03*
Y96260D03*
G54D95*
X342429Y316600D03*
Y314400D03*
X346429Y316600D03*
Y314400D03*
X516283Y318377D03*
X519283D03*
X516283Y320577D03*
X519283D03*
G54D69*
X222000Y858500D03*
G54D78*
X299474Y111000D03*
X332526D03*
G54D96*
X364700Y55500D03*
X376300D03*
X576300Y380500D03*
X564700D03*
X576300Y394000D03*
X564700D03*
X576300Y421000D03*
X564700D03*
X576300Y407500D03*
X564700D03*
X886200Y70500D03*
Y84500D03*
X897800Y70500D03*
Y84500D03*
X1247700Y176000D03*
Y189000D03*
X1259300Y176000D03*
Y189000D03*
G54D87*
X323214Y74290D03*
G54D88*
X317564Y80195D03*
Y76258D03*
Y78227D03*
X334280Y80195D03*
Y78227D03*
Y76258D03*
Y74290D03*
G54D79*
X286359Y430678D03*
X294959Y426938D03*
Y434418D03*
G54D97*
X360433Y140945D03*
X357284D03*
X360433Y144094D03*
X357284D03*
X360433Y147244D03*
X357284D03*
X360433Y150393D03*
X357284D03*
X360433Y153543D03*
X357284D03*
X360433Y156693D03*
X357284D03*
X360433Y159842D03*
X357284D03*
X360433Y162992D03*
X357284D03*
X360433Y166141D03*
X357284D03*
X360433Y169291D03*
X357284D03*
X360433Y172441D03*
X357284D03*
X360433Y175590D03*
X357284D03*
X360433Y178740D03*
X357284D03*
X360433Y181889D03*
X357284D03*
X360433Y185039D03*
X357284D03*
X360433Y188189D03*
X357284D03*
X360433Y191338D03*
X357284D03*
X360433Y194488D03*
X357284D03*
X360433Y197637D03*
X357284D03*
X360433Y200787D03*
X357284D03*
X360433Y203937D03*
X357284D03*
X360433Y207086D03*
X357284D03*
X360433Y210236D03*
X357284D03*
X360433Y213385D03*
X357284D03*
X379331Y131496D03*
X376181D03*
X373032D03*
X369882D03*
X366733D03*
X379331Y134645D03*
X376181D03*
X373032D03*
X369882D03*
X366733D03*
X379331Y137795D03*
X376181D03*
X373032D03*
X369882D03*
X366733D03*
X379331Y140945D03*
X376181D03*
X373032D03*
X369882D03*
X366733D03*
X363583D03*
X379331Y144094D03*
X376181D03*
X373032D03*
X369882D03*
X366733D03*
X363583D03*
X379331Y147244D03*
X376181D03*
X373032D03*
X369882D03*
X366733D03*
X363583D03*
X379331Y150393D03*
X376181D03*
X373032D03*
X369882D03*
X366733D03*
X363583D03*
X379331Y153543D03*
X376181D03*
X373032D03*
X369882D03*
X366733D03*
X363583D03*
X379331Y156693D03*
X376181D03*
X373032D03*
X369882D03*
X366733D03*
X363583D03*
X379331Y159842D03*
X376181D03*
X373032D03*
X369882D03*
X366733D03*
X363583D03*
X379331Y162992D03*
X376181D03*
X373032D03*
X369882D03*
X366733D03*
X363583D03*
X379331Y166141D03*
X376181D03*
X373032D03*
X369882D03*
X366733D03*
X363583D03*
X379331Y169291D03*
X376181D03*
X373032D03*
X369882D03*
X366733D03*
X363583D03*
X379331Y172441D03*
X376181D03*
X373032D03*
X369882D03*
X366733D03*
X363583D03*
X379331Y175590D03*
X376181D03*
X373032D03*
X369882D03*
X366733D03*
X363583D03*
X379331Y178740D03*
X376181D03*
X373032D03*
X369882D03*
X366733D03*
X363583D03*
X379331Y181889D03*
X376181D03*
X373032D03*
X369882D03*
X366733D03*
X363583D03*
X379331Y185039D03*
X376181D03*
X373032D03*
X369882D03*
X366733D03*
X363583D03*
X379331Y188189D03*
X376181D03*
X373032D03*
X369882D03*
X366733D03*
X363583D03*
X379331Y191338D03*
X376181D03*
X373032D03*
X369882D03*
X366733D03*
X363583D03*
X379331Y194488D03*
X376181D03*
X373032D03*
X369882D03*
X366733D03*
X363583D03*
X379331Y197637D03*
X376181D03*
X373032D03*
X369882D03*
X366733D03*
X363583D03*
X379331Y200787D03*
X376181D03*
X373032D03*
X369882D03*
X366733D03*
X363583D03*
X379331Y203937D03*
X376181D03*
X373032D03*
X369882D03*
X366733D03*
X363583D03*
X379331Y207086D03*
X376181D03*
X373032D03*
X369882D03*
X366733D03*
X363583D03*
X379331Y210236D03*
X376181D03*
X373032D03*
X369882D03*
X366733D03*
X363583D03*
X379331Y213385D03*
X376181D03*
X373032D03*
X369882D03*
X366733D03*
X363583D03*
X379331Y216535D03*
X376181D03*
X373032D03*
X369882D03*
X366733D03*
X379331Y219685D03*
X376181D03*
X373032D03*
X369882D03*
X366733D03*
X379331Y222834D03*
X376181D03*
X373032D03*
X369882D03*
X366733D03*
X395079Y131496D03*
X391929D03*
X388780D03*
X385630D03*
X382481D03*
X395079Y134645D03*
X391929D03*
X388780D03*
X385630D03*
X382481D03*
X395079Y137795D03*
X391929D03*
X388780D03*
X385630D03*
X382481D03*
X395079Y140945D03*
X391929D03*
X388780D03*
X385630D03*
X382481D03*
X395079Y144094D03*
X391929D03*
X388780D03*
X385630D03*
X382481D03*
X395079Y147244D03*
X391929D03*
X388780D03*
X385630D03*
X382481D03*
X395079Y150393D03*
X391929D03*
X388780D03*
X385630D03*
X382481D03*
X395079Y153543D03*
X391929D03*
X388780D03*
X385630D03*
X382481D03*
X395079Y156693D03*
X391929D03*
X388780D03*
X385630D03*
X382481D03*
X395079Y159842D03*
X391929D03*
X388780D03*
X385630D03*
X382481D03*
X395079Y162992D03*
X391929D03*
X388780D03*
X385630D03*
X382481D03*
X395079Y166141D03*
X391929D03*
X388780D03*
X385630D03*
X382481D03*
X395079Y169291D03*
X391929D03*
X388780D03*
X385630D03*
X382481D03*
X395079Y172441D03*
X391929D03*
X388780D03*
X385630D03*
X382481D03*
X395079Y175590D03*
X391929D03*
X388780D03*
X385630D03*
X382481D03*
X395079Y178740D03*
X391929D03*
X388780D03*
X385630D03*
X382481D03*
X395079Y181889D03*
X391929D03*
X388780D03*
X385630D03*
X382481D03*
X395079Y185039D03*
X391929D03*
X388780D03*
X385630D03*
X382481D03*
X395079Y188189D03*
X391929D03*
X388780D03*
X385630D03*
X382481D03*
X395079Y191338D03*
X391929D03*
X388780D03*
X385630D03*
X382481D03*
X395079Y194488D03*
X391929D03*
X388780D03*
X385630D03*
X382481D03*
X395079Y197637D03*
X391929D03*
X388780D03*
X385630D03*
X382481D03*
X395079Y200787D03*
X391929D03*
X388780D03*
X385630D03*
X382481D03*
X395079Y203937D03*
X391929D03*
X388780D03*
X385630D03*
X382481D03*
X395079Y207086D03*
X391929D03*
X388780D03*
X385630D03*
X382481D03*
X395079Y210236D03*
X391929D03*
X388780D03*
X385630D03*
X382481D03*
X395079Y213385D03*
X391929D03*
X388780D03*
X385630D03*
X382481D03*
X395079Y216535D03*
X391929D03*
X388780D03*
X385630D03*
X382481D03*
X395079Y219685D03*
X391929D03*
X388780D03*
X385630D03*
X382481D03*
X395079Y222834D03*
X391929D03*
X388780D03*
X385630D03*
X382481D03*
X410827Y131496D03*
X407677D03*
X404528D03*
X401378D03*
X398229D03*
X410827Y134645D03*
X407677D03*
X404528D03*
X401378D03*
X398229D03*
X410827Y137795D03*
X407677D03*
X404528D03*
X401378D03*
X398229D03*
X410827Y140945D03*
X407677D03*
X404528D03*
X401378D03*
X398229D03*
X410827Y144094D03*
X407677D03*
X404528D03*
X401378D03*
X398229D03*
X410827Y147244D03*
X407677D03*
X404528D03*
X401378D03*
X398229D03*
X410827Y150393D03*
X407677D03*
X404528D03*
X401378D03*
X398229D03*
X410827Y153543D03*
X407677D03*
X404528D03*
X401378D03*
X398229D03*
X410827Y156693D03*
X407677D03*
X404528D03*
X401378D03*
X398229D03*
X410827Y159842D03*
X407677D03*
X404528D03*
X401378D03*
X398229D03*
X410827Y162992D03*
X407677D03*
X404528D03*
X401378D03*
X398229D03*
X410827Y166141D03*
X407677D03*
X404528D03*
X401378D03*
X398229D03*
X410827Y169291D03*
X407677D03*
X404528D03*
X401378D03*
X398229D03*
X410827Y172441D03*
X407677D03*
X404528D03*
X401378D03*
X398229D03*
X410827Y175590D03*
X407677D03*
X404528D03*
X401378D03*
X398229D03*
X410827Y178740D03*
X407677D03*
X404528D03*
X401378D03*
X398229D03*
X410827Y181889D03*
X407677D03*
X404528D03*
X401378D03*
X398229D03*
X410827Y185039D03*
X407677D03*
X404528D03*
X401378D03*
X398229D03*
X410827Y188189D03*
X407677D03*
X404528D03*
X401378D03*
X398229D03*
X410827Y191338D03*
X407677D03*
X404528D03*
X401378D03*
X398229D03*
X410827Y194488D03*
X407677D03*
X404528D03*
X401378D03*
X398229D03*
X410827Y197637D03*
X407677D03*
X404528D03*
X401378D03*
X398229D03*
X410827Y200787D03*
X407677D03*
X404528D03*
X401378D03*
X398229D03*
X410827Y203937D03*
X407677D03*
X404528D03*
X401378D03*
X398229D03*
X410827Y207086D03*
X407677D03*
X404528D03*
X401378D03*
X398229D03*
X410827Y210236D03*
X407677D03*
X404528D03*
X401378D03*
X398229D03*
X410827Y213385D03*
X407677D03*
X404528D03*
X401378D03*
X398229D03*
X410827Y216535D03*
X407677D03*
X404528D03*
X401378D03*
X398229D03*
X410827Y219685D03*
X407677D03*
X404528D03*
X401378D03*
X398229D03*
X410827Y222834D03*
X407677D03*
X404528D03*
X401378D03*
X398229D03*
X426575Y131496D03*
X423425D03*
X420276D03*
X417126D03*
X413977D03*
X426575Y134645D03*
X423425D03*
X420276D03*
X417126D03*
X413977D03*
X426575Y137795D03*
X423425D03*
X420276D03*
X417126D03*
X413977D03*
X426575Y140945D03*
X423425D03*
X420276D03*
X417126D03*
X413977D03*
X426575Y144094D03*
X423425D03*
X420276D03*
X417126D03*
X413977D03*
X426575Y147244D03*
X423425D03*
X420276D03*
X417126D03*
X413977D03*
X426575Y150393D03*
X423425D03*
X420276D03*
X417126D03*
X413977D03*
X426575Y153543D03*
X423425D03*
X420276D03*
X417126D03*
X413977D03*
X426575Y156693D03*
X423425D03*
X420276D03*
X417126D03*
X413977D03*
X426575Y159842D03*
X423425D03*
X420276D03*
X417126D03*
X413977D03*
X426575Y162992D03*
X423425D03*
X420276D03*
X417126D03*
X413977D03*
X426575Y166141D03*
X423425D03*
X420276D03*
X417126D03*
X413977D03*
X426575Y169291D03*
X423425D03*
X420276D03*
X417126D03*
X413977D03*
X426575Y172441D03*
X423425D03*
X420276D03*
X417126D03*
X413977D03*
X426575Y175590D03*
X423425D03*
X420276D03*
X417126D03*
X413977D03*
X426575Y178740D03*
X423425D03*
X420276D03*
X417126D03*
X413977D03*
X426575Y181889D03*
X423425D03*
X420276D03*
X417126D03*
X413977D03*
X426575Y185039D03*
X423425D03*
X420276D03*
X417126D03*
X413977D03*
X426575Y188189D03*
X423425D03*
X420276D03*
X417126D03*
X413977D03*
X426575Y191338D03*
X423425D03*
X420276D03*
X417126D03*
X413977D03*
X426575Y194488D03*
X423425D03*
X420276D03*
X417126D03*
X413977D03*
X426575Y197637D03*
X423425D03*
X420276D03*
X417126D03*
X413977D03*
X426575Y200787D03*
X423425D03*
X420276D03*
X417126D03*
X413977D03*
X426575Y203937D03*
X423425D03*
X420276D03*
X417126D03*
X413977D03*
X426575Y207086D03*
X423425D03*
X420276D03*
X417126D03*
X413977D03*
X426575Y210236D03*
X423425D03*
X420276D03*
X417126D03*
X413977D03*
X426575Y213385D03*
X423425D03*
X420276D03*
X417126D03*
X413977D03*
X426575Y216535D03*
X423425D03*
X420276D03*
X417126D03*
X413977D03*
X426575Y219685D03*
X423425D03*
X420276D03*
X417126D03*
X413977D03*
X426575Y222834D03*
X423425D03*
X420276D03*
X417126D03*
X413977D03*
X439173Y131496D03*
X436024D03*
X432874D03*
X429725D03*
X439173Y134645D03*
X436024D03*
X432874D03*
X429725D03*
X439173Y137795D03*
X436024D03*
X432874D03*
X429725D03*
X442323Y140945D03*
X439173D03*
X436024D03*
X432874D03*
X429725D03*
X442323Y144094D03*
X439173D03*
X436024D03*
X432874D03*
X429725D03*
X442323Y147244D03*
X439173D03*
X436024D03*
X432874D03*
X429725D03*
X442323Y150393D03*
X439173D03*
X436024D03*
X432874D03*
X429725D03*
X442323Y153543D03*
X439173D03*
X436024D03*
X432874D03*
X429725D03*
X442323Y156693D03*
X439173D03*
X436024D03*
X432874D03*
X429725D03*
X442323Y159842D03*
X439173D03*
X436024D03*
X432874D03*
X429725D03*
X442323Y162992D03*
X439173D03*
X436024D03*
X432874D03*
X429725D03*
X442323Y166141D03*
X439173D03*
X436024D03*
X432874D03*
X429725D03*
X442323Y169291D03*
X439173D03*
X436024D03*
X432874D03*
X429725D03*
X442323Y172441D03*
X439173D03*
X436024D03*
X432874D03*
X429725D03*
X442323Y175590D03*
X439173D03*
X436024D03*
X432874D03*
X429725D03*
X442323Y178740D03*
X439173D03*
X436024D03*
X432874D03*
X429725D03*
X442323Y181889D03*
X439173D03*
X436024D03*
X432874D03*
X429725D03*
X442323Y185039D03*
X439173D03*
X436024D03*
X432874D03*
X429725D03*
X442323Y188189D03*
X439173D03*
X436024D03*
X432874D03*
X429725D03*
X442323Y191338D03*
X439173D03*
X436024D03*
X432874D03*
X429725D03*
X442323Y194488D03*
X439173D03*
X436024D03*
X432874D03*
X429725D03*
X442323Y197637D03*
X439173D03*
X436024D03*
X432874D03*
X429725D03*
X442323Y200787D03*
X439173D03*
X436024D03*
X432874D03*
X429725D03*
X442323Y203937D03*
X439173D03*
X436024D03*
X432874D03*
X429725D03*
X442323Y207086D03*
X439173D03*
X436024D03*
X432874D03*
X429725D03*
X442323Y210236D03*
X439173D03*
X436024D03*
X432874D03*
X429725D03*
X442323Y213385D03*
X439173D03*
X436024D03*
X432874D03*
X429725D03*
X439173Y216535D03*
X436024D03*
X432874D03*
X429725D03*
X439173Y219685D03*
X436024D03*
X432874D03*
X429725D03*
X439173Y222834D03*
X436024D03*
X432874D03*
X429725D03*
X448622Y140945D03*
X445473D03*
X448622Y144094D03*
X445473D03*
X448622Y147244D03*
X445473D03*
X448622Y150393D03*
X445473D03*
X448622Y153543D03*
X445473D03*
X448622Y156693D03*
X445473D03*
X448622Y159842D03*
X445473D03*
X448622Y162992D03*
X445473D03*
X448622Y166141D03*
X445473D03*
X448622Y169291D03*
X445473D03*
X448622Y172441D03*
X445473D03*
X448622Y175590D03*
X445473D03*
X448622Y178740D03*
X445473D03*
X448622Y181889D03*
X445473D03*
X448622Y185039D03*
X445473D03*
X448622Y188189D03*
X445473D03*
X448622Y191338D03*
X445473D03*
X448622Y194488D03*
X445473D03*
X448622Y197637D03*
X445473D03*
X448622Y200787D03*
X445473D03*
X448622Y203937D03*
X445473D03*
X448622Y207086D03*
X445473D03*
X448622Y210236D03*
X445473D03*
X448622Y213385D03*
X445473D03*
X1130846Y662363D03*
X1133996D03*
X1130846Y659213D03*
X1133996D03*
X1121397Y678111D03*
X1124547D03*
X1127696D03*
X1130846D03*
X1133996D03*
X1121397Y674961D03*
X1124547D03*
X1127696D03*
X1130846D03*
X1133996D03*
X1121397Y671812D03*
X1124547D03*
X1127696D03*
X1130846D03*
X1133996D03*
X1121397Y668662D03*
X1124547D03*
X1127696D03*
X1130846D03*
X1133996D03*
X1130846Y665512D03*
X1133996D03*
X1121397Y697008D03*
X1124547D03*
X1127696D03*
X1130846D03*
X1133996D03*
X1121397Y693859D03*
X1124547D03*
X1127696D03*
X1130846D03*
X1133996D03*
X1121397Y690709D03*
X1124547D03*
X1127696D03*
X1130846D03*
X1133996D03*
X1121397Y687560D03*
X1124547D03*
X1127696D03*
X1130846D03*
X1133996D03*
X1121397Y684410D03*
X1124547D03*
X1127696D03*
X1130846D03*
X1133996D03*
X1121397Y681260D03*
X1124547D03*
X1127696D03*
X1130846D03*
X1133996D03*
X1121397Y712756D03*
X1124547D03*
X1127696D03*
X1130846D03*
X1133996D03*
X1121397Y709607D03*
X1124547D03*
X1127696D03*
X1130846D03*
X1133996D03*
X1121397Y706457D03*
X1124547D03*
X1127696D03*
X1130846D03*
X1133996D03*
X1121397Y703308D03*
X1124547D03*
X1127696D03*
X1130846D03*
X1133996D03*
X1121397Y700158D03*
X1124547D03*
X1127696D03*
X1130846D03*
X1133996D03*
X1130846Y725355D03*
X1133996D03*
X1130846Y722205D03*
X1133996D03*
X1130846Y719056D03*
X1133996D03*
X1121397Y715906D03*
X1124547D03*
X1127696D03*
X1130846D03*
X1133996D03*
X1121646Y772186D03*
Y775335D03*
Y778485D03*
X1124796Y772186D03*
Y775335D03*
Y778485D03*
X1127945Y772186D03*
Y775335D03*
Y778485D03*
X1131095Y772186D03*
Y775335D03*
Y778485D03*
X1134244Y772186D03*
Y775335D03*
Y778485D03*
X1121646Y791083D03*
Y794233D03*
X1124796Y791083D03*
Y794233D03*
X1127945Y791083D03*
Y794233D03*
X1131095Y791083D03*
Y794233D03*
X1134244Y791083D03*
Y794233D03*
X1121646Y797382D03*
X1124796D03*
X1127945D03*
X1131095D03*
X1134244D03*
X1137145Y662363D03*
X1140295D03*
X1143444D03*
X1146594D03*
X1149744D03*
X1137145Y659213D03*
X1140295D03*
X1143444D03*
X1146594D03*
X1149744D03*
X1143444Y674961D03*
X1146594D03*
X1149744D03*
X1137145Y671812D03*
X1140295D03*
X1143444D03*
X1146594D03*
X1149744D03*
X1137145Y668662D03*
X1140295D03*
X1143444D03*
X1146594D03*
X1149744D03*
X1137145Y665512D03*
X1140295D03*
X1143444D03*
X1146594D03*
X1149744D03*
X1137145Y697008D03*
X1146594D03*
X1149744D03*
X1137145Y693859D03*
X1146594D03*
X1149744D03*
X1137145Y690709D03*
X1146594D03*
X1149744D03*
X1137145Y687560D03*
X1146594D03*
X1149744D03*
X1137145Y684410D03*
X1146594D03*
X1149744D03*
X1137145Y681260D03*
Y712756D03*
X1140295D03*
X1143444D03*
X1146594D03*
X1149744D03*
X1143444Y709607D03*
X1146594D03*
X1149744D03*
X1137145Y703308D03*
Y700158D03*
X1146594D03*
X1149744D03*
X1137145Y725355D03*
X1140295D03*
X1143444D03*
X1146594D03*
X1149744D03*
X1137145Y722205D03*
X1140295D03*
X1143444D03*
X1146594D03*
X1149744D03*
X1137145Y719056D03*
X1140295D03*
X1143444D03*
X1146594D03*
X1149744D03*
X1137145Y715906D03*
X1140295D03*
X1143444D03*
X1146594D03*
X1149744D03*
X1137394Y772186D03*
Y775335D03*
Y778485D03*
X1140544Y772186D03*
Y775335D03*
Y778485D03*
X1143693Y772186D03*
Y775335D03*
Y778485D03*
X1146843Y772186D03*
Y775335D03*
Y778485D03*
X1149992Y772186D03*
Y775335D03*
Y778485D03*
X1137394Y791083D03*
Y794233D03*
X1140544Y791083D03*
Y794233D03*
X1143693Y791083D03*
Y794233D03*
X1146843Y791083D03*
Y794233D03*
X1149992Y791083D03*
Y794233D03*
X1137394Y797382D03*
X1140544D03*
X1143693D03*
X1146843D03*
X1149992D03*
X1152893Y662363D03*
X1156043D03*
X1159192D03*
X1162342D03*
X1165492D03*
X1152893Y659213D03*
X1156043D03*
X1159192D03*
X1162342D03*
X1165492D03*
X1152893Y674961D03*
X1156043D03*
X1159192D03*
X1162342D03*
X1165492D03*
X1152893Y671812D03*
X1156043D03*
X1159192D03*
X1162342D03*
X1165492D03*
X1152893Y668662D03*
X1156043D03*
X1159192D03*
X1162342D03*
X1165492D03*
X1152893Y665512D03*
X1156043D03*
X1159192D03*
X1162342D03*
X1165492D03*
X1152893Y697008D03*
X1156043D03*
X1159192D03*
X1162342D03*
X1152893Y693859D03*
X1156043D03*
X1159192D03*
X1162342D03*
X1152893Y690709D03*
X1156043D03*
X1159192D03*
X1162342D03*
X1152893Y687560D03*
X1156043D03*
X1159192D03*
X1162342D03*
X1152893Y684410D03*
X1156043D03*
X1159192D03*
X1162342D03*
X1152893Y712756D03*
X1156043D03*
X1159192D03*
X1162342D03*
X1165492D03*
X1152893Y709607D03*
X1156043D03*
X1159192D03*
X1162342D03*
X1165492D03*
X1152893Y700158D03*
X1156043D03*
X1159192D03*
X1162342D03*
X1152893Y725355D03*
X1156043D03*
X1159192D03*
X1162342D03*
X1165492D03*
X1152893Y722205D03*
X1156043D03*
X1159192D03*
X1162342D03*
X1165492D03*
X1152893Y719056D03*
X1156043D03*
X1159192D03*
X1162342D03*
X1165492D03*
X1152893Y715906D03*
X1156043D03*
X1159192D03*
X1162342D03*
X1165492D03*
X1153142Y772186D03*
Y775335D03*
Y778485D03*
X1156292Y772186D03*
Y775335D03*
Y778485D03*
X1159441Y772186D03*
Y775335D03*
Y778485D03*
X1162591Y772186D03*
Y775335D03*
Y778485D03*
X1165740Y772186D03*
Y775335D03*
Y778485D03*
X1153142Y791083D03*
Y794233D03*
X1156292Y791083D03*
Y794233D03*
X1159441Y791083D03*
Y794233D03*
X1162591Y791083D03*
Y794233D03*
X1165740Y791083D03*
Y794233D03*
X1153142Y797382D03*
X1156292D03*
X1159441D03*
X1162591D03*
X1165740D03*
X1168641Y662363D03*
X1171791D03*
X1174940D03*
X1178090D03*
X1168641Y659213D03*
X1171791D03*
X1174940D03*
X1178090D03*
X1174940Y678111D03*
X1178090D03*
X1181240D03*
X1174940Y674961D03*
X1178090D03*
X1181240D03*
X1168641Y671812D03*
X1171791D03*
X1174940D03*
X1178090D03*
X1181240D03*
X1168641Y668662D03*
X1171791D03*
X1174940D03*
X1178090D03*
X1181240D03*
X1168641Y665512D03*
X1171791D03*
X1174940D03*
X1178090D03*
X1171791Y697008D03*
X1174940D03*
X1178090D03*
X1181240D03*
X1171791Y693859D03*
X1174940D03*
X1178090D03*
X1181240D03*
X1171791Y690709D03*
X1174940D03*
X1178090D03*
X1181240D03*
X1171791Y687560D03*
X1174940D03*
X1178090D03*
X1181240D03*
X1171791Y684410D03*
X1174940D03*
X1178090D03*
X1181240D03*
X1171791Y681260D03*
X1174940D03*
X1178090D03*
X1181240D03*
X1168641Y712756D03*
X1171791D03*
X1174940D03*
X1178090D03*
X1181240D03*
X1174940Y709607D03*
X1178090D03*
X1181240D03*
X1174940Y706457D03*
X1178090D03*
X1181240D03*
X1171791Y703308D03*
X1174940D03*
X1178090D03*
X1181240D03*
X1171791Y700158D03*
X1174940D03*
X1178090D03*
X1181240D03*
X1168641Y725355D03*
X1171791D03*
X1174940D03*
X1178090D03*
X1168641Y722205D03*
X1171791D03*
X1174940D03*
X1178090D03*
X1168641Y719056D03*
X1171791D03*
X1174940D03*
X1178090D03*
X1168641Y715906D03*
X1171791D03*
X1174940D03*
X1178090D03*
X1181240D03*
X1168890Y772186D03*
Y775335D03*
Y778485D03*
Y791083D03*
Y794233D03*
Y797382D03*
X1184389Y678111D03*
X1187539D03*
X1184389Y674961D03*
X1187539D03*
X1184389Y671812D03*
X1187539D03*
X1184389Y668662D03*
X1187539D03*
X1184389Y697008D03*
X1187539D03*
X1184389Y693859D03*
X1187539D03*
X1184389Y690709D03*
X1187539D03*
X1184389Y687560D03*
X1187539D03*
X1184389Y684410D03*
X1187539D03*
X1184389Y681260D03*
X1187539D03*
X1184389Y712756D03*
X1187539D03*
X1184389Y709607D03*
X1187539D03*
X1184389Y706457D03*
X1187539D03*
X1184389Y703308D03*
X1187539D03*
X1184389Y700158D03*
X1187539D03*
X1184389Y715906D03*
X1187539D03*
G54D89*
X321001Y83632D03*
X319032D03*
X322969D03*
X324938D03*
X326906D03*
X328875D03*
X332812D03*
X330843D03*
G54D98*
X373894Y7992D03*
X386264D03*
X421138D03*
X433508D03*
G54D99*
X402953Y23622D03*
X413189D03*
X423425D03*
M02*
